FILE_TYPE = MACRO_DRAWING;
SET COLOR_WIRE YELLOW;
SET COLOR_PROP ORANGE;
SET COLOR_DOT WHITE;
SET COLOR_ARC YELLOW;
SET COLOR_BODY GREEN;
SET COLOR_NOTE PURPLE;
SET PROP_DISPLAY VALUE;
SET PAGE_NUMBER P68;
FORCEADD GND_SG..1
(-11900 6850);
FORCEPROP 3 LASTPIN (-11850 6900) SIG_NAME SG\g
J 0
(-11840 6910);
DISPLAY 0.659574 (-11840 6910);
PAINT MONO (-11840 6910);
DISPLAY INVISIBLE (-11840 6910);
FORCEPROP 1 LAST HDL_POWER SG
J 1
(-11845 6755);
DISPLAY 0.808511 (-11845 6755);
PAINT GREEN (-11845 6755);
FORCEPROP 2 LAST CDS_LIB cls
J 0
(-11900 6850);
DISPLAY INVISIBLE (-11900 6850);
FORCEPROP 1 LAST CDS_LMAN_SYM_OUTLINE 0,0,100,-50
J 0
(-11900 6850);
DISPLAY 0.468085 (-11900 6850);
PAINT GREEN (-11900 6850);
DISPLAY INVISIBLE (-11900 6850);
FORCEPROP 1 LAST BODY_TYPE PLUMBING
J 0
(-11885 6835);
DISPLAY 0.808511 (-11885 6835);
PAINT GREEN (-11885 6835);
DISPLAY INVISIBLE (-11885 6835);
FORCEPROP 1 LAST PATH I1
J 0
(-11865 6850);
DISPLAY 0.808511 (-11865 6850);
PAINT GREEN (-11865 6850);
DISPLAY INVISIBLE (-11865 6850);
FORCEADD RESISTOR..1
(-6950 7000);
FORCEPROP 1 LAST $LOCATION R181
J 2
(-6951 7055);
DISPLAY 1.212766 (-6951 7055);
PAINT GREEN (-6951 7055);
FORCEPROP 2 LAST CDS_LOCATION R181
J 0
(-7100 7200);
DISPLAY 1.021277 (-7100 7200);
DISPLAY INVISIBLE (-7100 7200);
FORCEPROP 2 LAST $SEC 1
J 0
(-7100 7200);
DISPLAY 0.680851 (-7100 7200);
PAINT MONO (-7100 7200);
DISPLAY INVISIBLE (-7100 7200);
FORCEPROP 2 LAST CDS_SEC 1
J 0
(-7100 7200);
DISPLAY 1.021277 (-7100 7200);
DISPLAY INVISIBLE (-7100 7200);
FORCEPROP 2 LASTPIN (-7050 7000) $PN 1
J 2
(-7060 7010);
DISPLAY 0.680851 (-7060 7010);
PAINT MONO (-7060 7010);
FORCEPROP 2 LASTPIN (-6800 7000) $PN 2
J 0
(-6790 7010);
DISPLAY 0.680851 (-6790 7010);
PAINT MONO (-6790 7010);
FORCEPROP 0 LAST PACKAGE 0402
J 0
(-7000 6900);
DISPLAY 1.021277 (-7000 6900);
FORCEPROP 1 LAST VALUE 0OHM
J 0
(-6911 7055);
DISPLAY 1.212766 (-6911 7055);
PAINT GREEN (-6911 7055);
FORCEPROP 2 LAST CDS_LIB passive
J 0
(-6950 7000);
DISPLAY INVISIBLE (-6950 7000);
FORCEPROP 1 LAST CDS_LMAN_SYM_OUTLINE -50,50,100,-50
J 0
(-6950 7000);
DISPLAY 0.468085 (-6950 7000);
PAINT GREEN (-6950 7000);
DISPLAY INVISIBLE (-6950 7000);
FORCEPROP 1 LAST CLS_PN G155-100R0-J0
J 0
(-7086 7200);
DISPLAY 1.212766 (-7086 7200);
PAINT GREEN (-7086 7200);
DISPLAY INVISIBLE (-7086 7200);
FORCEPROP 1 LAST TOLERANCE -
J 0
(-7147 7255);
DISPLAY 1.212766 (-7147 7255);
PAINT GREEN (-7147 7255);
DISPLAY INVISIBLE (-7147 7255);
FORCEPROP 1 LAST PATH I10
J 0
(-7147 7105);
DISPLAY 1.212766 (-7147 7105);
PAINT GREEN (-7147 7105);
DISPLAY INVISIBLE (-7147 7105);
FORCEADD RESISTOR..2
(-7600 7300);
FORCEPROP 1 LAST $LOCATION R178
J 0
(-7550 7150);
DISPLAY 1.212766 (-7550 7150);
PAINT GREEN (-7550 7150);
FORCEPROP 2 LAST CDS_LOCATION R178
J 0
(-7750 7500);
DISPLAY 1.021277 (-7750 7500);
DISPLAY INVISIBLE (-7750 7500);
FORCEPROP 2 LAST $SEC 1
J 0
(-7750 7500);
DISPLAY 0.680851 (-7750 7500);
PAINT MONO (-7750 7500);
DISPLAY INVISIBLE (-7750 7500);
FORCEPROP 2 LAST CDS_SEC 1
J 0
(-7750 7500);
DISPLAY 1.021277 (-7750 7500);
DISPLAY INVISIBLE (-7750 7500);
FORCEPROP 2 LASTPIN (-7600 7400) $PN 1
R 1
J 0
(-7610 7410);
DISPLAY 0.680851 (-7610 7410);
PAINT MONO (-7610 7410);
FORCEPROP 2 LASTPIN (-7600 7150) $PN 2
R 1
J 2
(-7610 7140);
DISPLAY 0.680851 (-7610 7140);
PAINT MONO (-7610 7140);
FORCEPROP 0 LAST PACKAGE 0402
J 0
(-7550 7400);
DISPLAY 1.021277 (-7550 7400);
FORCEPROP 1 LAST VALUE 4.7KOHM
J 0
(-7550 7250);
DISPLAY 1.212766 (-7550 7250);
PAINT GREEN (-7550 7250);
FORCEPROP 1 LAST CLS_PN G155-14701-01
J 0
(-7350 7350);
DISPLAY 1.212766 (-7350 7350);
PAINT GREEN (-7350 7350);
DISPLAY INVISIBLE (-7350 7350);
FORCEPROP 2 LAST CDS_LIB passive
J 0
(-7600 7300);
DISPLAY INVISIBLE (-7600 7300);
FORCEPROP 1 LAST CDS_LMAN_SYM_OUTLINE -50,50,50,-100
J 0
(-7600 7300);
DISPLAY 0.468085 (-7600 7300);
PAINT GREEN (-7600 7300);
DISPLAY INVISIBLE (-7600 7300);
FORCEPROP 1 LAST TOLERANCE 1%
J 0
(-7350 7150);
DISPLAY 1.212766 (-7350 7150);
PAINT GREEN (-7350 7150);
DISPLAY INVISIBLE (-7350 7150);
FORCEPROP 1 LAST PATH I11
J 0
(-7797 7405);
DISPLAY 1.212766 (-7797 7405);
PAINT GREEN (-7797 7405);
DISPLAY INVISIBLE (-7797 7405);
FORCEADD VCC..1
(-7650 7550);
FORCEPROP 3 LASTPIN (-7600 7500) SIG_NAME XP3R3V\g
J 0
(-7590 7510);
DISPLAY 0.659574 (-7590 7510);
PAINT MONO (-7590 7510);
DISPLAY INVISIBLE (-7590 7510);
FORCEPROP 0 LAST VOLTAGE 3.3
J 0
(-7850 7650);
DISPLAY 1.021277 (-7850 7650);
DISPLAY BOTH (-7850 7650);
FORCEPROP 1 LAST HDL_POWER XP3R3V
J 1
(-7595 7605);
DISPLAY 1.021277 (-7595 7605);
PAINT GREEN (-7595 7605);
FORCEPROP 2 LAST CDS_LIB cls
J 0
(-7650 7550);
DISPLAY INVISIBLE (-7650 7550);
FORCEPROP 1 LAST CDS_LMAN_SYM_OUTLINE -250,250,250,-250
J 0
(-7650 7550);
DISPLAY 0.468085 (-7650 7550);
PAINT GREEN (-7650 7550);
DISPLAY INVISIBLE (-7650 7550);
FORCEPROP 1 LAST BODY_TYPE PLUMBING
J 0
(-7695 7507);
DISPLAY 0.340426 (-7695 7507);
PAINT GREEN (-7695 7507);
DISPLAY INVISIBLE (-7695 7507);
FORCEPROP 1 LAST PATH I12
J 0
(-7615 7640);
DISPLAY 0.808511 (-7615 7640);
PAINT GREEN (-7615 7640);
DISPLAY INVISIBLE (-7615 7640);
FORCEADD OFFPAGE_OUT..1
(-5750 7000);
FORCEPROP 2 LAST $XR1 30J2< 
J 0
(-5485 7000);
DISPLAY 0.638298 (-5485 7000);
PAINT MONO (-5485 7000);
FORCEPROP 2 LAST $XR0 25F6<> 
J 0
(-5695 7000);
DISPLAY 0.638298 (-5695 7000);
PAINT MONO (-5695 7000);
FORCEPROP 2 LAST CDS_LIB cls
J 2
(-5750 7000);
DISPLAY INVISIBLE (-5750 7000);
FORCEPROP 1 LAST CDS_LMAN_SYM_OUTLINE -50,50,50,-50
J 0
(-5750 7000);
DISPLAY 0.468085 (-5750 7000);
PAINT GREEN (-5750 7000);
DISPLAY INVISIBLE (-5750 7000);
FORCEPROP 1 LAST BODY_TYPE COMMENT
J 0
(-5740 7135);
DISPLAY 0.808511 (-5740 7135);
PAINT GREEN (-5740 7135);
DISPLAY INVISIBLE (-5740 7135);
FORCEPROP 1 LAST OFFPAGE TRUE
J 0
(-5740 7055);
DISPLAY 0.808511 (-5740 7055);
PAINT GREEN (-5740 7055);
DISPLAY INVISIBLE (-5740 7055);
FORCEPROP 2 LAST PATH I13
J 0
(-5700 7100);
DISPLAY 1.021277 (-5700 7100);
DISPLAY INVISIBLE (-5700 7100);
FORCEADD RESISTOR..1
R 1
(-6350 7650);
FORCEPROP 1 LAST $LOCATION R186
R 1
J 2
(-6405 7749);
DISPLAY 1.212766 (-6405 7749);
PAINT GREEN (-6405 7749);
FORCEPROP 0 LAST CDS_LOCATION R186
R 1
J 0
(-6300 7850);
DISPLAY 1.021277 (-6300 7850);
DISPLAY INVISIBLE (-6300 7850);
FORCEPROP 0 LAST $SEC 1
R 1
J 0
(-6300 7850);
DISPLAY 0.680851 (-6300 7850);
PAINT MONO (-6300 7850);
DISPLAY INVISIBLE (-6300 7850);
FORCEPROP 0 LAST CDS_SEC 1
R 1
J 0
(-6300 7850);
DISPLAY 1.021277 (-6300 7850);
DISPLAY INVISIBLE (-6300 7850);
FORCEPROP 0 LASTPIN (-6350 7550) $PN 1
R 1
J 2
(-6360 7540);
DISPLAY 0.680851 (-6360 7540);
PAINT MONO (-6360 7540);
FORCEPROP 0 LASTPIN (-6350 7800) $PN 2
R 1
J 0
(-6360 7810);
DISPLAY 0.680851 (-6360 7810);
PAINT MONO (-6360 7810);
FORCEPROP 1 LAST VALUE 3KOHM
R 1
J 0
(-6255 7439);
DISPLAY 1.212766 (-6255 7439);
PAINT GREEN (-6255 7439);
FORCEPROP 0 LAST PACKAGE 0402
R 1
J 0
(-6500 7450);
DISPLAY 1.021277 (-6500 7450);
FORCEPROP 1 LAST CLS_PN G155-03001-01
R 1
J 0
(-6550 7514);
DISPLAY 1.212766 (-6550 7514);
PAINT GREEN (-6550 7514);
DISPLAY INVISIBLE (-6550 7514);
FORCEPROP 1 LAST CDS_LMAN_SYM_OUTLINE -50,50,100,-50
R 1
J 0
(-6350 7650);
DISPLAY 0.468085 (-6350 7650);
PAINT GREEN (-6350 7650);
DISPLAY INVISIBLE (-6350 7650);
FORCEPROP 2 LAST CDS_LIB passive
R 1
J 0
(-6350 7650);
DISPLAY INVISIBLE (-6350 7650);
FORCEPROP 1 LAST TOLERANCE 1%
R 1
J 0
(-6605 7453);
DISPLAY 1.212766 (-6605 7453);
PAINT GREEN (-6605 7453);
DISPLAY INVISIBLE (-6605 7453);
FORCEPROP 1 LAST PATH I14
R 1
J 0
(-6455 7453);
DISPLAY 1.212766 (-6455 7453);
PAINT GREEN (-6455 7453);
DISPLAY INVISIBLE (-6455 7453);
FORCEADD GND_SG..1
(-6150 7300);
FORCEPROP 3 LASTPIN (-6100 7350) SIG_NAME SG\g
J 0
(-6090 7360);
DISPLAY 0.659574 (-6090 7360);
PAINT MONO (-6090 7360);
DISPLAY INVISIBLE (-6090 7360);
FORCEPROP 1 LAST HDL_POWER SG
J 1
(-6100 7200);
DISPLAY 0.808511 (-6100 7200);
PAINT GREEN (-6100 7200);
FORCEPROP 1 LAST CDS_LMAN_SYM_OUTLINE 0,0,100,-50
J 0
(-6150 7300);
DISPLAY 0.468085 (-6150 7300);
PAINT GREEN (-6150 7300);
DISPLAY INVISIBLE (-6150 7300);
FORCEPROP 2 LAST CDS_LIB cls
J 0
(-6150 7300);
DISPLAY INVISIBLE (-6150 7300);
FORCEPROP 1 LAST BODY_TYPE PLUMBING
J 0
(-6135 7285);
DISPLAY 0.808511 (-6135 7285);
PAINT GREEN (-6135 7285);
DISPLAY INVISIBLE (-6135 7285);
FORCEPROP 1 LAST PATH I15
J 0
(-6115 7300);
DISPLAY 0.808511 (-6115 7300);
PAINT GREEN (-6115 7300);
DISPLAY INVISIBLE (-6115 7300);
FORCEADD RESISTOR..1
R 1
(-6100 7650);
FORCEPROP 1 LAST $LOCATION R189
R 1
J 2
(-6155 7749);
DISPLAY 1.212766 (-6155 7749);
PAINT GREEN (-6155 7749);
FORCEPROP 0 LAST CDS_LOCATION R189
R 1
J 0
(-6050 7850);
DISPLAY 1.021277 (-6050 7850);
DISPLAY INVISIBLE (-6050 7850);
FORCEPROP 0 LAST $SEC 1
R 1
J 0
(-6050 7850);
DISPLAY 0.680851 (-6050 7850);
PAINT MONO (-6050 7850);
DISPLAY INVISIBLE (-6050 7850);
FORCEPROP 0 LAST CDS_SEC 1
R 1
J 0
(-6050 7850);
DISPLAY 1.021277 (-6050 7850);
DISPLAY INVISIBLE (-6050 7850);
FORCEPROP 0 LASTPIN (-6100 7550) $PN 1
R 1
J 2
(-6110 7540);
DISPLAY 0.680851 (-6110 7540);
PAINT MONO (-6110 7540);
FORCEPROP 0 LASTPIN (-6100 7800) $PN 2
R 1
J 0
(-6110 7810);
DISPLAY 0.680851 (-6110 7810);
PAINT MONO (-6110 7810);
FORCEPROP 1 LAST VALUE 3.24KOHM
R 1
J 0
(-6005 7439);
DISPLAY 1.212766 (-6005 7439);
PAINT GREEN (-6005 7439);
FORCEPROP 0 LAST NO_ASSY TRUE
J 0
(-5950 7750);
DISPLAY 1.021277 (-5950 7750);
DISPLAY BOTH (-5950 7750);
FORCEPROP 0 LAST PACKAGE 0402
R 1
J 0
(-5900 7500);
DISPLAY 1.021277 (-5900 7500);
FORCEPROP 1 LAST CLS_PN G155-03241-01
R 1
J 0
(-6300 7514);
DISPLAY 1.212766 (-6300 7514);
PAINT GREEN (-6300 7514);
DISPLAY INVISIBLE (-6300 7514);
FORCEPROP 1 LAST CDS_LMAN_SYM_OUTLINE -50,50,100,-50
R 1
J 0
(-6100 7650);
DISPLAY 0.468085 (-6100 7650);
PAINT GREEN (-6100 7650);
DISPLAY INVISIBLE (-6100 7650);
FORCEPROP 2 LAST CDS_LIB passive
J 0
(-6100 7650);
DISPLAY INVISIBLE (-6100 7650);
FORCEPROP 1 LAST TOLERANCE 1%
R 1
J 0
(-6355 7453);
DISPLAY 1.212766 (-6355 7453);
PAINT GREEN (-6355 7453);
DISPLAY INVISIBLE (-6355 7453);
FORCEPROP 1 LAST PATH I16
R 1
J 0
(-6205 7453);
DISPLAY 1.212766 (-6205 7453);
PAINT GREEN (-6205 7453);
DISPLAY INVISIBLE (-6205 7453);
FORCEADD GND_SG..1
(-5200 7700);
FORCEPROP 3 LASTPIN (-5150 7750) SIG_NAME SG\g
J 0
(-5140 7760);
DISPLAY 0.659574 (-5140 7760);
PAINT MONO (-5140 7760);
DISPLAY INVISIBLE (-5140 7760);
FORCEPROP 1 LAST HDL_POWER SG
J 1
(-5150 7550);
DISPLAY 0.808511 (-5150 7550);
PAINT GREEN (-5150 7550);
FORCEPROP 1 LAST CDS_LMAN_SYM_OUTLINE 0,0,100,-50
J 0
(-5200 7700);
DISPLAY 0.468085 (-5200 7700);
PAINT GREEN (-5200 7700);
DISPLAY INVISIBLE (-5200 7700);
FORCEPROP 2 LAST CDS_LIB cls
J 0
(-5200 7700);
DISPLAY INVISIBLE (-5200 7700);
FORCEPROP 1 LAST BODY_TYPE PLUMBING
J 0
(-5185 7685);
DISPLAY 0.808511 (-5185 7685);
PAINT GREEN (-5185 7685);
DISPLAY INVISIBLE (-5185 7685);
FORCEPROP 1 LAST PATH I17
J 0
(-5165 7700);
DISPLAY 0.808511 (-5165 7700);
PAINT GREEN (-5165 7700);
DISPLAY INVISIBLE (-5165 7700);
FORCEADD RESISTOR..1
(-12450 7750);
FORCEPROP 1 LAST $LOCATION R140
J 2
(-12350 7800);
DISPLAY 1.212766 (-12350 7800);
PAINT GREEN (-12350 7800);
FORCEPROP 0 LAST CDS_LOCATION R140
J 0
(-12300 7900);
DISPLAY 1.021277 (-12300 7900);
DISPLAY INVISIBLE (-12300 7900);
FORCEPROP 2 LAST $SEC 1
J 0
(-12600 7950);
DISPLAY 0.680851 (-12600 7950);
PAINT MONO (-12600 7950);
DISPLAY INVISIBLE (-12600 7950);
FORCEPROP 0 LAST CDS_SEC 1
J 0
(-12300 7900);
DISPLAY 1.021277 (-12300 7900);
DISPLAY INVISIBLE (-12300 7900);
FORCEPROP 2 LASTPIN (-12550 7750) $PN 1
J 2
(-12560 7760);
DISPLAY 0.680851 (-12560 7760);
PAINT MONO (-12560 7760);
FORCEPROP 2 LASTPIN (-12300 7750) $PN 2
J 0
(-12290 7760);
DISPLAY 0.680851 (-12290 7760);
PAINT MONO (-12290 7760);
FORCEPROP 0 LAST PACKAGE 0402
J 0
(-12500 7900);
DISPLAY 1.021277 (-12500 7900);
FORCEPROP 1 LAST VALUE 0OHM
J 0
(-12511 7655);
DISPLAY 1.212766 (-12511 7655);
PAINT GREEN (-12511 7655);
FORCEPROP 1 LAST CLS_PN G155-100R0-J0
J 0
(-12586 7950);
DISPLAY 1.212766 (-12586 7950);
PAINT GREEN (-12586 7950);
DISPLAY INVISIBLE (-12586 7950);
FORCEPROP 2 LAST CDS_LIB passive
J 0
(-12450 7750);
DISPLAY INVISIBLE (-12450 7750);
FORCEPROP 1 LAST CDS_LMAN_SYM_OUTLINE -50,50,100,-50
J 0
(-12450 7750);
DISPLAY 0.468085 (-12450 7750);
PAINT GREEN (-12450 7750);
DISPLAY INVISIBLE (-12450 7750);
FORCEPROP 1 LAST TOLERANCE -
J 0
(-12647 8005);
DISPLAY 1.212766 (-12647 8005);
PAINT GREEN (-12647 8005);
DISPLAY INVISIBLE (-12647 8005);
FORCEPROP 1 LAST PATH I18
J 0
(-12647 7855);
DISPLAY 1.212766 (-12647 7855);
PAINT GREEN (-12647 7855);
DISPLAY INVISIBLE (-12647 7855);
FORCEADD OFFPAGE_IN..1
(-13650 7750);
FORCEPROP 2 LAST $XR1 29G1> 
J 0
(-14044 7750);
DISPLAY 0.638298 (-14044 7750);
PAINT MONO (-14044 7750);
FORCEPROP 2 LAST $XR0 25F6<> 
J 0
(-13864 7750);
DISPLAY 0.638298 (-13864 7750);
PAINT MONO (-13864 7750);
FORCEPROP 1 LAST BODY_TYPE COMMENT
J 0
(-13640 7885);
DISPLAY 0.808511 (-13640 7885);
PAINT GREEN (-13640 7885);
DISPLAY INVISIBLE (-13640 7885);
FORCEPROP 1 LAST CDS_LMAN_SYM_OUTLINE -50,50,50,-50
J 0
(-13650 7750);
DISPLAY 0.468085 (-13650 7750);
PAINT GREEN (-13650 7750);
DISPLAY INVISIBLE (-13650 7750);
FORCEPROP 2 LAST CDS_LIB cls
J 0
(-13650 7750);
DISPLAY INVISIBLE (-13650 7750);
FORCEPROP 1 LAST OFFPAGE TRUE
J 0
(-13640 7805);
DISPLAY 0.808511 (-13640 7805);
PAINT GREEN (-13640 7805);
DISPLAY INVISIBLE (-13640 7805);
FORCEPROP 2 LAST PATH I19
J 0
(-13600 7850);
DISPLAY 1.021277 (-13600 7850);
DISPLAY INVISIBLE (-13600 7850);
FORCEADD RESISTOR..2
(-11850 7550);
FORCEPROP 1 LAST $LOCATION R165
J 0
(-11800 7400);
DISPLAY 1.212766 (-11800 7400);
PAINT GREEN (-11800 7400);
FORCEPROP 0 LAST CDS_LOCATION R165
J 0
(-11800 7700);
DISPLAY 1.021277 (-11800 7700);
DISPLAY INVISIBLE (-11800 7700);
FORCEPROP 0 LAST $SEC 1
J 0
(-11800 7700);
DISPLAY 0.680851 (-11800 7700);
PAINT MONO (-11800 7700);
DISPLAY INVISIBLE (-11800 7700);
FORCEPROP 0 LAST CDS_SEC 1
J 0
(-11800 7700);
DISPLAY 1.021277 (-11800 7700);
DISPLAY INVISIBLE (-11800 7700);
FORCEPROP 0 LASTPIN (-11850 7650) $PN 1
R 1
J 0
(-11860 7660);
DISPLAY 0.680851 (-11860 7660);
PAINT MONO (-11860 7660);
FORCEPROP 0 LASTPIN (-11850 7400) $PN 2
R 1
J 2
(-11860 7390);
DISPLAY 0.680851 (-11860 7390);
PAINT MONO (-11860 7390);
FORCEPROP 0 LAST PACKAGE 0402
J 0
(-11800 7500);
DISPLAY 1.021277 (-11800 7500);
FORCEPROP 0 LAST NO_ASSY TRUE
J 0
(-12500 7450);
DISPLAY 1.021277 (-12500 7450);
DISPLAY BOTH (-12500 7450);
FORCEPROP 1 LAST VALUE 10KOHM
J 0
(-11800 7600);
DISPLAY 1.212766 (-11800 7600);
PAINT GREEN (-11800 7600);
FORCEPROP 2 LAST CDS_LIB passive
J 0
(-11850 7550);
DISPLAY INVISIBLE (-11850 7550);
FORCEPROP 1 LAST CDS_LMAN_SYM_OUTLINE -50,50,50,-100
J 0
(-11850 7550);
DISPLAY 0.468085 (-11850 7550);
PAINT GREEN (-11850 7550);
DISPLAY INVISIBLE (-11850 7550);
FORCEPROP 1 LAST CLS_PN G155-11002-01
J 0
(-11986 7750);
DISPLAY 1.212766 (-11986 7750);
PAINT GREEN (-11986 7750);
DISPLAY INVISIBLE (-11986 7750);
FORCEPROP 1 LAST TOLERANCE 1%
J 0
(-12047 7805);
DISPLAY 1.212766 (-12047 7805);
PAINT GREEN (-12047 7805);
DISPLAY INVISIBLE (-12047 7805);
FORCEPROP 1 LAST PATH I2
J 0
(-12047 7655);
DISPLAY 1.212766 (-12047 7655);
PAINT GREEN (-12047 7655);
DISPLAY INVISIBLE (-12047 7655);
FORCEADD VCC..1
(-13350 8950);
FORCEPROP 3 LASTPIN (-13300 8900) SIG_NAME XP3R3V\g
J 0
(-13290 8910);
DISPLAY 0.659574 (-13290 8910);
PAINT MONO (-13290 8910);
DISPLAY INVISIBLE (-13290 8910);
FORCEPROP 0 LAST VOLTAGE 3.3
J 0
(-13550 9050);
DISPLAY 1.021277 (-13550 9050);
DISPLAY BOTH (-13550 9050);
FORCEPROP 1 LAST HDL_POWER XP3R3V
J 1
(-13295 9005);
DISPLAY 1.021277 (-13295 9005);
PAINT GREEN (-13295 9005);
FORCEPROP 2 LAST CDS_LIB cls
J 0
(-13350 8950);
DISPLAY INVISIBLE (-13350 8950);
FORCEPROP 1 LAST CDS_LMAN_SYM_OUTLINE -250,250,250,-250
J 0
(-13350 8950);
DISPLAY 0.468085 (-13350 8950);
PAINT GREEN (-13350 8950);
DISPLAY INVISIBLE (-13350 8950);
FORCEPROP 1 LAST BODY_TYPE PLUMBING
J 0
(-13395 8907);
DISPLAY 0.340426 (-13395 8907);
PAINT GREEN (-13395 8907);
DISPLAY INVISIBLE (-13395 8907);
FORCEPROP 1 LAST PATH I20
J 0
(-13315 9040);
DISPLAY 0.808511 (-13315 9040);
PAINT GREEN (-13315 9040);
DISPLAY INVISIBLE (-13315 9040);
FORCEADD OFFPAGE_IN..1
(-13600 2850);
FORCEPROP 2 LAST $XR1 30E11> 
J 0
(-14024 2850);
DISPLAY 0.638298 (-14024 2850);
PAINT MONO (-14024 2850);
FORCEPROP 2 LAST $XR0 25F6<> 
J 0
(-13814 2850);
DISPLAY 0.638298 (-13814 2850);
PAINT MONO (-13814 2850);
FORCEPROP 2 LAST CDS_LIB cls
J 0
(-13600 2850);
DISPLAY INVISIBLE (-13600 2850);
FORCEPROP 1 LAST CDS_LMAN_SYM_OUTLINE -50,50,50,-50
J 0
(-13600 2850);
DISPLAY 0.468085 (-13600 2850);
PAINT GREEN (-13600 2850);
DISPLAY INVISIBLE (-13600 2850);
FORCEPROP 1 LAST BODY_TYPE COMMENT
J 0
(-13590 2985);
DISPLAY 0.808511 (-13590 2985);
PAINT GREEN (-13590 2985);
DISPLAY INVISIBLE (-13590 2985);
FORCEPROP 1 LAST OFFPAGE TRUE
J 0
(-13590 2905);
DISPLAY 0.808511 (-13590 2905);
PAINT GREEN (-13590 2905);
DISPLAY INVISIBLE (-13590 2905);
FORCEPROP 2 LAST PATH I23
J 0
(-13550 2950);
DISPLAY 1.021277 (-13550 2950);
DISPLAY INVISIBLE (-13550 2950);
FORCEADD VCC..1
(-13250 4000);
FORCEPROP 3 LASTPIN (-13200 3950) SIG_NAME XP3R3V\g
J 0
(-13190 3960);
DISPLAY 0.659574 (-13190 3960);
PAINT MONO (-13190 3960);
DISPLAY INVISIBLE (-13190 3960);
FORCEPROP 0 LAST VOLTAGE 3.3
J 0
(-13450 4100);
DISPLAY 1.021277 (-13450 4100);
DISPLAY BOTH (-13450 4100);
FORCEPROP 1 LAST HDL_POWER XP3R3V
J 1
(-13195 4055);
DISPLAY 1.021277 (-13195 4055);
PAINT GREEN (-13195 4055);
FORCEPROP 2 LAST CDS_LIB cls
J 0
(-13250 4000);
DISPLAY INVISIBLE (-13250 4000);
FORCEPROP 1 LAST CDS_LMAN_SYM_OUTLINE -250,250,250,-250
J 0
(-13250 4000);
DISPLAY 0.468085 (-13250 4000);
PAINT GREEN (-13250 4000);
DISPLAY INVISIBLE (-13250 4000);
FORCEPROP 1 LAST BODY_TYPE PLUMBING
J 0
(-13295 3957);
DISPLAY 0.340426 (-13295 3957);
PAINT GREEN (-13295 3957);
DISPLAY INVISIBLE (-13295 3957);
FORCEPROP 1 LAST PATH I24
J 0
(-13215 4090);
DISPLAY 0.808511 (-13215 4090);
PAINT GREEN (-13215 4090);
DISPLAY INVISIBLE (-13215 4090);
FORCEADD FERRITEBEAD..1
(-12500 8800);
FORCEPROP 1 LAST $LOCATION L11
J 2
(-12560 8859);
DISPLAY 1.212766 (-12560 8859);
PAINT GREEN (-12560 8859);
FORCEPROP 2 LAST CDS_LOCATION L11
J 0
(-12200 8950);
DISPLAY 1.021277 (-12200 8950);
DISPLAY INVISIBLE (-12200 8950);
FORCEPROP 2 LAST $SEC 1
J 0
(-12200 8950);
DISPLAY 0.680851 (-12200 8950);
PAINT MONO (-12200 8950);
DISPLAY INVISIBLE (-12200 8950);
FORCEPROP 2 LAST CDS_SEC 1
J 0
(-12200 8950);
DISPLAY 1.021277 (-12200 8950);
DISPLAY INVISIBLE (-12200 8950);
FORCEPROP 2 LASTPIN (-12600 8750) $PN 1
J 2
(-12610 8760);
DISPLAY 0.680851 (-12610 8760);
PAINT MONO (-12610 8760);
FORCEPROP 2 LASTPIN (-12200 8750) $PN 2
J 0
(-12190 8760);
DISPLAY 0.680851 (-12190 8760);
PAINT MONO (-12190 8760);
FORCEPROP 0 LAST PACKAGE 0603
J 0
(-12450 8850);
DISPLAY 1.021277 (-12450 8850);
FORCEPROP 1 LAST VALUE 26OHM
J 0
(-12200 8850);
DISPLAY 1.212766 (-12200 8850);
PAINT GREEN (-12200 8850);
FORCEPROP 1 LAST CLS_PN G191-10101-01
J 2
(-12550 8850);
DISPLAY 1.212766 (-12550 8850);
PAINT GREEN (-12550 8850);
DISPLAY INVISIBLE (-12550 8850);
FORCEPROP 2 LAST CDS_LIB passive
J 0
(-12500 8800);
DISPLAY INVISIBLE (-12500 8800);
FORCEPROP 1 LAST CDS_LMAN_SYM_OUTLINE 0,0,200,-100
J 0
(-12500 8800);
DISPLAY 0.468085 (-12500 8800);
PAINT GREEN (-12500 8800);
DISPLAY INVISIBLE (-12500 8800);
FORCEPROP 1 LAST PATH I25
J 2
(-12550 8850);
DISPLAY 1.212766 (-12550 8850);
PAINT GREEN (-12550 8850);
DISPLAY INVISIBLE (-12550 8850);
FORCEPROP 1 LAST TOLERANCE 25%
J 0
(-12600 8850);
DISPLAY 1.212766 (-12600 8850);
PAINT GREEN (-12600 8850);
DISPLAY INVISIBLE (-12600 8850);
FORCEADD RESISTOR..2
(-11700 8300);
FORCEPROP 1 LAST $LOCATION R177
J 0
(-12000 8150);
DISPLAY 1.212766 (-12000 8150);
PAINT GREEN (-12000 8150);
FORCEPROP 0 LAST CDS_LOCATION R177
J 0
(-11650 8450);
DISPLAY 1.021277 (-11650 8450);
DISPLAY INVISIBLE (-11650 8450);
FORCEPROP 0 LAST $SEC 1
J 0
(-11650 8450);
DISPLAY 0.680851 (-11650 8450);
PAINT MONO (-11650 8450);
DISPLAY INVISIBLE (-11650 8450);
FORCEPROP 0 LAST CDS_SEC 1
J 0
(-11650 8450);
DISPLAY 1.021277 (-11650 8450);
DISPLAY INVISIBLE (-11650 8450);
FORCEPROP 0 LASTPIN (-11700 8400) $PN 1
R 1
J 0
(-11710 8410);
DISPLAY 0.680851 (-11710 8410);
PAINT MONO (-11710 8410);
FORCEPROP 0 LASTPIN (-11700 8150) $PN 2
R 1
J 2
(-11710 8140);
DISPLAY 0.680851 (-11710 8140);
PAINT MONO (-11710 8140);
FORCEPROP 1 LAST VALUE 1.13KOHM
J 0
(-12250 8250);
DISPLAY 1.212766 (-12250 8250);
PAINT GREEN (-12250 8250);
FORCEPROP 0 LAST NO_ASSY TRUE
J 0
(-12300 8350);
DISPLAY 1.021277 (-12300 8350);
DISPLAY BOTH (-12300 8350);
FORCEPROP 0 LAST PACKAGE 0402
J 0
(-12050 8450);
DISPLAY 1.021277 (-12050 8450);
FORCEPROP 1 LAST CLS_PN G152-00055-01
J 0
(-11836 8500);
DISPLAY 1.212766 (-11836 8500);
PAINT GREEN (-11836 8500);
DISPLAY INVISIBLE (-11836 8500);
FORCEPROP 1 LAST CDS_LMAN_SYM_OUTLINE -50,50,50,-100
J 0
(-11700 8300);
DISPLAY 0.468085 (-11700 8300);
PAINT GREEN (-11700 8300);
DISPLAY INVISIBLE (-11700 8300);
FORCEPROP 2 LAST CDS_LIB passive
J 0
(-11700 8300);
DISPLAY INVISIBLE (-11700 8300);
FORCEPROP 1 LAST TOLERANCE 1%
J 0
(-11897 8555);
DISPLAY 1.212766 (-11897 8555);
PAINT GREEN (-11897 8555);
DISPLAY INVISIBLE (-11897 8555);
FORCEPROP 1 LAST PATH I26
J 0
(-11897 8405);
DISPLAY 1.212766 (-11897 8405);
PAINT GREEN (-11897 8405);
DISPLAY INVISIBLE (-11897 8405);
FORCEADD CAPACITOR..2
(-11250 8450);
FORCEPROP 1 LAST $LOCATION C185
J 0
(-11150 8600);
DISPLAY 1.212766 (-11150 8600);
PAINT GREEN (-11150 8600);
FORCEPROP 2 LAST CDS_LOCATION C185
J 0
(-11150 8700);
DISPLAY 1.021277 (-11150 8700);
DISPLAY INVISIBLE (-11150 8700);
FORCEPROP 2 LAST $SEC 1
J 0
(-11150 8700);
DISPLAY 0.680851 (-11150 8700);
PAINT MONO (-11150 8700);
DISPLAY INVISIBLE (-11150 8700);
FORCEPROP 2 LAST CDS_SEC 1
J 0
(-11150 8700);
DISPLAY 1.021277 (-11150 8700);
DISPLAY INVISIBLE (-11150 8700);
FORCEPROP 2 LASTPIN (-11250 8550) $PN 1
R 1
J 0
(-11260 8560);
DISPLAY 0.680851 (-11260 8560);
PAINT MONO (-11260 8560);
FORCEPROP 2 LASTPIN (-11250 8300) $PN 2
R 1
J 2
(-11260 8290);
DISPLAY 0.680851 (-11260 8290);
PAINT MONO (-11260 8290);
FORCEPROP 0 LAST VOLTAGE 25V
J 0
(-11150 8300);
DISPLAY 1.021277 (-11150 8300);
FORCEPROP 1 LAST VALUE 10UF
J 0
(-11200 8525);
DISPLAY 1.212766 (-11200 8525);
PAINT GREEN (-11200 8525);
FORCEPROP 0 LAST PACKAGE 0805
J 0
(-11150 8400);
DISPLAY 1.021277 (-11150 8400);
FORCEPROP 2 LAST CDS_LIB passive
J 0
(-11250 8450);
DISPLAY INVISIBLE (-11250 8450);
FORCEPROP 1 LAST CDS_LMAN_SYM_OUTLINE -50,0,50,-50
J 0
(-11250 8450);
DISPLAY 0.468085 (-11250 8450);
PAINT GREEN (-11250 8450);
DISPLAY INVISIBLE (-11250 8450);
FORCEPROP 1 LAST TOLERANCE 20%
J 0
(-11400 8550);
DISPLAY 1.212766 (-11400 8550);
PAINT GREEN (-11400 8550);
DISPLAY INVISIBLE (-11400 8550);
FORCEPROP 1 LAST CLS_PN G107-0F106-EM
J 0
(-11350 8500);
DISPLAY 1.212766 (-11350 8500);
PAINT GREEN (-11350 8500);
DISPLAY INVISIBLE (-11350 8500);
FORCEPROP 1 LAST PATH I27
J 0
(-11350 8500);
DISPLAY 1.212766 (-11350 8500);
PAINT GREEN (-11350 8500);
DISPLAY INVISIBLE (-11350 8500);
FORCEADD CAPACITOR..2
(-11300 7500);
FORCEPROP 1 LAST $LOCATION C184
J 0
(-11200 7400);
DISPLAY 1.212766 (-11200 7400);
PAINT GREEN (-11200 7400);
FORCEPROP 0 LAST CDS_LOCATION C184
J 0
(-11200 7750);
DISPLAY 1.021277 (-11200 7750);
DISPLAY INVISIBLE (-11200 7750);
FORCEPROP 0 LAST $SEC 1
J 0
(-11200 7750);
DISPLAY 0.680851 (-11200 7750);
PAINT MONO (-11200 7750);
DISPLAY INVISIBLE (-11200 7750);
FORCEPROP 0 LAST CDS_SEC 1
J 0
(-11200 7750);
DISPLAY 1.021277 (-11200 7750);
DISPLAY INVISIBLE (-11200 7750);
FORCEPROP 0 LASTPIN (-11300 7600) $PN 1
R 1
J 0
(-11310 7610);
DISPLAY 0.680851 (-11310 7610);
PAINT MONO (-11310 7610);
FORCEPROP 0 LASTPIN (-11300 7350) $PN 2
R 1
J 2
(-11310 7340);
DISPLAY 0.680851 (-11310 7340);
PAINT MONO (-11310 7340);
FORCEPROP 1 LAST VALUE 0.1UF
J 0
(-11250 7300);
DISPLAY 1.212766 (-11250 7300);
PAINT GREEN (-11250 7300);
FORCEPROP 0 LAST PACKAGE 0402
J 0
(-11200 7550);
DISPLAY 1.021277 (-11200 7550);
FORCEPROP 0 LAST VOLTAGE 25V
J 0
(-11200 7650);
DISPLAY 1.021277 (-11200 7650);
FORCEPROP 1 LAST TOLERANCE 10%
J 0
(-11450 7600);
DISPLAY 1.212766 (-11450 7600);
PAINT GREEN (-11450 7600);
DISPLAY INVISIBLE (-11450 7600);
FORCEPROP 1 LAST CDS_LMAN_SYM_OUTLINE -50,0,50,-50
J 0
(-11300 7500);
DISPLAY 0.468085 (-11300 7500);
PAINT GREEN (-11300 7500);
DISPLAY INVISIBLE (-11300 7500);
FORCEPROP 2 LAST CDS_LIB passive
J 0
(-11300 7500);
DISPLAY INVISIBLE (-11300 7500);
FORCEPROP 1 LAST CLS_PN G105-0B104-EK
J 0
(-11400 7550);
DISPLAY 1.212766 (-11400 7550);
PAINT GREEN (-11400 7550);
DISPLAY INVISIBLE (-11400 7550);
FORCEPROP 1 LAST PATH I3
J 0
(-11400 7550);
DISPLAY 1.212766 (-11400 7550);
PAINT GREEN (-11400 7550);
DISPLAY INVISIBLE (-11400 7550);
FORCEADD GND_SG..1
(-10850 8000);
FORCEPROP 3 LASTPIN (-10800 8050) SIG_NAME SG\g
J 0
(-10790 8060);
DISPLAY 0.659574 (-10790 8060);
PAINT MONO (-10790 8060);
DISPLAY INVISIBLE (-10790 8060);
FORCEPROP 2 LAST VOLTAGE 0
J 0
(-10750 7950);
DISPLAY 1.021277 (-10750 7950);
FORCEPROP 1 LAST HDL_POWER SG
J 1
(-10795 7905);
DISPLAY 0.808511 (-10795 7905);
PAINT GREEN (-10795 7905);
FORCEPROP 1 LAST CDS_LMAN_SYM_OUTLINE 0,0,100,-50
J 0
(-10850 8000);
DISPLAY 0.468085 (-10850 8000);
PAINT GREEN (-10850 8000);
DISPLAY INVISIBLE (-10850 8000);
FORCEPROP 2 LAST CDS_LIB cls
J 0
(-10850 8000);
DISPLAY INVISIBLE (-10850 8000);
FORCEPROP 1 LAST BODY_TYPE PLUMBING
J 0
(-10835 7985);
DISPLAY 0.808511 (-10835 7985);
PAINT GREEN (-10835 7985);
DISPLAY INVISIBLE (-10835 7985);
FORCEPROP 1 LAST PATH I34
J 0
(-10815 8000);
DISPLAY 0.808511 (-10815 8000);
PAINT GREEN (-10815 8000);
DISPLAY INVISIBLE (-10815 8000);
FORCEADD CAPACITOR..2
(-10800 8450);
FORCEPROP 1 LAST $LOCATION C188
J 0
(-10700 8600);
DISPLAY 1.212766 (-10700 8600);
PAINT GREEN (-10700 8600);
FORCEPROP 0 LAST CDS_LOCATION C188
J 0
(-10700 8700);
DISPLAY 1.021277 (-10700 8700);
DISPLAY INVISIBLE (-10700 8700);
FORCEPROP 0 LAST $SEC 1
J 0
(-10700 8700);
DISPLAY 0.680851 (-10700 8700);
PAINT MONO (-10700 8700);
DISPLAY INVISIBLE (-10700 8700);
FORCEPROP 0 LAST CDS_SEC 1
J 0
(-10700 8700);
DISPLAY 1.021277 (-10700 8700);
DISPLAY INVISIBLE (-10700 8700);
FORCEPROP 0 LASTPIN (-10800 8550) $PN 1
R 1
J 0
(-10810 8560);
DISPLAY 0.680851 (-10810 8560);
PAINT MONO (-10810 8560);
FORCEPROP 0 LASTPIN (-10800 8300) $PN 2
R 1
J 2
(-10810 8290);
DISPLAY 0.680851 (-10810 8290);
PAINT MONO (-10810 8290);
FORCEPROP 0 LAST VOLTAGE 25V
J 0
(-10700 8300);
DISPLAY 1.021277 (-10700 8300);
FORCEPROP 0 LAST PACKAGE 0402
J 0
(-10700 8400);
DISPLAY 1.021277 (-10700 8400);
FORCEPROP 1 LAST VALUE 0.1UF
J 0
(-10750 8500);
DISPLAY 1.212766 (-10750 8500);
PAINT GREEN (-10750 8500);
FORCEPROP 1 LAST TOLERANCE 10%
J 0
(-10950 8550);
DISPLAY 1.212766 (-10950 8550);
PAINT GREEN (-10950 8550);
DISPLAY INVISIBLE (-10950 8550);
FORCEPROP 1 LAST CLS_PN G105-0B104-EK
J 0
(-10900 8500);
DISPLAY 1.212766 (-10900 8500);
PAINT GREEN (-10900 8500);
DISPLAY INVISIBLE (-10900 8500);
FORCEPROP 1 LAST CDS_LMAN_SYM_OUTLINE -50,0,50,-50
J 0
(-10800 8450);
DISPLAY 0.468085 (-10800 8450);
PAINT GREEN (-10800 8450);
DISPLAY INVISIBLE (-10800 8450);
FORCEPROP 2 LAST CDS_LIB passive
J 0
(-10800 8450);
DISPLAY INVISIBLE (-10800 8450);
FORCEPROP 1 LAST PATH I35
J 0
(-10900 8500);
DISPLAY 1.212766 (-10900 8500);
PAINT GREEN (-10900 8500);
DISPLAY INVISIBLE (-10900 8500);
FORCEADD GND_SG..1
(-10750 6850);
FORCEPROP 3 LASTPIN (-10700 6900) SIG_NAME SG\g
J 0
(-10690 6910);
DISPLAY 0.659574 (-10690 6910);
PAINT MONO (-10690 6910);
DISPLAY INVISIBLE (-10690 6910);
FORCEPROP 2 LAST VOLTAGE 0
J 0
(-10650 6800);
DISPLAY 1.021277 (-10650 6800);
FORCEPROP 1 LAST HDL_POWER SG
J 1
(-10695 6755);
DISPLAY 0.808511 (-10695 6755);
PAINT GREEN (-10695 6755);
FORCEPROP 2 LAST CDS_LIB cls
J 0
(-10750 6850);
PAINT BLUE (-10750 6850);
DISPLAY INVISIBLE (-10750 6850);
FORCEPROP 1 LAST CDS_LMAN_SYM_OUTLINE 0,0,100,-50
J 0
(-10750 6850);
DISPLAY 0.468085 (-10750 6850);
PAINT GREEN (-10750 6850);
DISPLAY INVISIBLE (-10750 6850);
FORCEPROP 1 LAST BODY_TYPE PLUMBING
J 0
(-10735 6835);
DISPLAY 0.808511 (-10735 6835);
PAINT GREEN (-10735 6835);
DISPLAY INVISIBLE (-10735 6835);
FORCEPROP 1 LAST PATH I4
J 0
(-10715 6850);
DISPLAY 0.808511 (-10715 6850);
PAINT GREEN (-10715 6850);
DISPLAY INVISIBLE (-10715 6850);
FORCEADD GND_SG..1
(-11850 1950);
FORCEPROP 3 LASTPIN (-11800 2000) SIG_NAME SG\g
J 0
(-11790 2010);
DISPLAY 0.659574 (-11790 2010);
PAINT MONO (-11790 2010);
DISPLAY INVISIBLE (-11790 2010);
FORCEPROP 1 LAST HDL_POWER SG
J 1
(-11795 1855);
DISPLAY 0.808511 (-11795 1855);
PAINT GREEN (-11795 1855);
FORCEPROP 1 LAST CDS_LMAN_SYM_OUTLINE 0,0,100,-50
J 0
(-11850 1950);
DISPLAY 0.468085 (-11850 1950);
PAINT GREEN (-11850 1950);
DISPLAY INVISIBLE (-11850 1950);
FORCEPROP 2 LAST CDS_LIB cls
J 0
(-11850 1950);
DISPLAY INVISIBLE (-11850 1950);
FORCEPROP 1 LAST BODY_TYPE PLUMBING
J 0
(-11835 1935);
DISPLAY 0.808511 (-11835 1935);
PAINT GREEN (-11835 1935);
DISPLAY INVISIBLE (-11835 1935);
FORCEPROP 1 LAST PATH I41
J 0
(-11815 1950);
DISPLAY 0.808511 (-11815 1950);
PAINT GREEN (-11815 1950);
DISPLAY INVISIBLE (-11815 1950);
FORCEADD RESISTOR..1
(-12200 2850);
FORCEPROP 1 LAST $LOCATION R141
J 2
(-12151 2905);
DISPLAY 1.212766 (-12151 2905);
PAINT GREEN (-12151 2905);
FORCEPROP 0 LAST CDS_LOCATION R141
J 0
(-12050 3000);
DISPLAY 1.021277 (-12050 3000);
DISPLAY INVISIBLE (-12050 3000);
FORCEPROP 2 LAST $SEC 1
J 0
(-12350 3050);
DISPLAY 0.680851 (-12350 3050);
PAINT MONO (-12350 3050);
DISPLAY INVISIBLE (-12350 3050);
FORCEPROP 0 LAST CDS_SEC 1
J 0
(-12050 3000);
DISPLAY 1.021277 (-12050 3000);
DISPLAY INVISIBLE (-12050 3000);
FORCEPROP 2 LASTPIN (-12300 2850) $PN 1
J 2
(-12310 2860);
DISPLAY 0.680851 (-12310 2860);
PAINT MONO (-12310 2860);
FORCEPROP 2 LASTPIN (-12050 2850) $PN 2
J 0
(-12040 2860);
DISPLAY 0.680851 (-12040 2860);
PAINT MONO (-12040 2860);
FORCEPROP 0 LAST PACKAGE 0402
J 0
(-12150 3050);
DISPLAY 1.021277 (-12150 3050);
FORCEPROP 1 LAST VALUE 0OHM
J 0
(-12261 2755);
DISPLAY 1.212766 (-12261 2755);
PAINT GREEN (-12261 2755);
FORCEPROP 1 LAST CLS_PN G155-100R0-J0
J 0
(-12336 3050);
DISPLAY 1.212766 (-12336 3050);
PAINT GREEN (-12336 3050);
DISPLAY INVISIBLE (-12336 3050);
FORCEPROP 2 LAST CDS_LIB passive
J 0
(-12200 2850);
DISPLAY INVISIBLE (-12200 2850);
FORCEPROP 1 LAST CDS_LMAN_SYM_OUTLINE -50,50,100,-50
J 0
(-12200 2850);
DISPLAY 0.468085 (-12200 2850);
PAINT GREEN (-12200 2850);
DISPLAY INVISIBLE (-12200 2850);
FORCEPROP 1 LAST TOLERANCE -
J 0
(-12397 3105);
DISPLAY 1.212766 (-12397 3105);
PAINT GREEN (-12397 3105);
DISPLAY INVISIBLE (-12397 3105);
FORCEPROP 1 LAST PATH I42
J 0
(-12397 2955);
DISPLAY 1.212766 (-12397 2955);
PAINT GREEN (-12397 2955);
DISPLAY INVISIBLE (-12397 2955);
FORCEADD FERRITEBEAD..1
(-12450 3900);
FORCEPROP 1 LAST $LOCATION L6
J 2
(-12510 3959);
DISPLAY 1.212766 (-12510 3959);
PAINT GREEN (-12510 3959);
FORCEPROP 2 LAST CDS_LOCATION L6
J 0
(-12150 4050);
DISPLAY 1.021277 (-12150 4050);
DISPLAY INVISIBLE (-12150 4050);
FORCEPROP 2 LAST $SEC 1
J 0
(-12150 4050);
DISPLAY 0.680851 (-12150 4050);
PAINT MONO (-12150 4050);
DISPLAY INVISIBLE (-12150 4050);
FORCEPROP 2 LAST CDS_SEC 1
J 0
(-12150 4050);
DISPLAY 1.021277 (-12150 4050);
DISPLAY INVISIBLE (-12150 4050);
FORCEPROP 2 LASTPIN (-12550 3850) $PN 1
J 2
(-12560 3860);
DISPLAY 0.680851 (-12560 3860);
PAINT MONO (-12560 3860);
FORCEPROP 2 LASTPIN (-12150 3850) $PN 2
J 0
(-12140 3860);
DISPLAY 0.680851 (-12140 3860);
PAINT MONO (-12140 3860);
FORCEPROP 0 LAST PACKAGE 0603
J 0
(-12450 3950);
DISPLAY 1.021277 (-12450 3950);
FORCEPROP 1 LAST VALUE 26OHM
J 0
(-12150 3950);
DISPLAY 1.212766 (-12150 3950);
PAINT GREEN (-12150 3950);
FORCEPROP 1 LAST CLS_PN G191-10101-01
J 2
(-12500 3950);
DISPLAY 1.212766 (-12500 3950);
PAINT GREEN (-12500 3950);
DISPLAY INVISIBLE (-12500 3950);
FORCEPROP 2 LAST CDS_LIB passive
J 0
(-12450 3900);
DISPLAY INVISIBLE (-12450 3900);
FORCEPROP 1 LAST CDS_LMAN_SYM_OUTLINE 0,0,200,-100
J 0
(-12450 3900);
DISPLAY 0.468085 (-12450 3900);
PAINT GREEN (-12450 3900);
DISPLAY INVISIBLE (-12450 3900);
FORCEPROP 1 LAST PATH I43
J 2
(-12500 3950);
DISPLAY 1.212766 (-12500 3950);
PAINT GREEN (-12500 3950);
DISPLAY INVISIBLE (-12500 3950);
FORCEPROP 1 LAST TOLERANCE 25%
J 0
(-12550 3950);
DISPLAY 1.212766 (-12550 3950);
PAINT GREEN (-12550 3950);
DISPLAY INVISIBLE (-12550 3950);
FORCEADD RESISTOR..2
(-11800 2550);
FORCEPROP 1 LAST $LOCATION R174
J 0
(-11750 2400);
DISPLAY 1.212766 (-11750 2400);
PAINT GREEN (-11750 2400);
FORCEPROP 0 LAST CDS_LOCATION R174
J 0
(-11750 2700);
DISPLAY 1.021277 (-11750 2700);
DISPLAY INVISIBLE (-11750 2700);
FORCEPROP 0 LAST $SEC 1
J 0
(-11750 2700);
DISPLAY 0.680851 (-11750 2700);
PAINT MONO (-11750 2700);
DISPLAY INVISIBLE (-11750 2700);
FORCEPROP 0 LAST CDS_SEC 1
J 0
(-11750 2700);
DISPLAY 1.021277 (-11750 2700);
DISPLAY INVISIBLE (-11750 2700);
FORCEPROP 0 LASTPIN (-11800 2650) $PN 1
R 1
J 0
(-11810 2660);
DISPLAY 0.680851 (-11810 2660);
PAINT MONO (-11810 2660);
FORCEPROP 0 LASTPIN (-11800 2400) $PN 2
R 1
J 2
(-11810 2390);
DISPLAY 0.680851 (-11810 2390);
PAINT MONO (-11810 2390);
FORCEPROP 0 LAST PACKAGE 0402
J 0
(-11750 2750);
DISPLAY 1.021277 (-11750 2750);
FORCEPROP 0 LAST NO_ASSY TRUE
J 0
(-12350 2500);
DISPLAY 0.808511 (-12350 2500);
DISPLAY BOTH (-12350 2500);
FORCEPROP 1 LAST VALUE 10KOHM
J 0
(-11750 2600);
DISPLAY 1.212766 (-11750 2600);
PAINT GREEN (-11750 2600);
FORCEPROP 2 LAST CDS_LIB passive
J 0
(-11800 2550);
DISPLAY INVISIBLE (-11800 2550);
FORCEPROP 1 LAST CDS_LMAN_SYM_OUTLINE -50,50,50,-100
J 0
(-11800 2550);
DISPLAY 0.468085 (-11800 2550);
PAINT GREEN (-11800 2550);
DISPLAY INVISIBLE (-11800 2550);
FORCEPROP 1 LAST CLS_PN G155-11002-01
J 0
(-11936 2750);
DISPLAY 1.212766 (-11936 2750);
PAINT GREEN (-11936 2750);
DISPLAY INVISIBLE (-11936 2750);
FORCEPROP 1 LAST TOLERANCE 1%
J 0
(-11997 2805);
DISPLAY 1.212766 (-11997 2805);
PAINT GREEN (-11997 2805);
DISPLAY INVISIBLE (-11997 2805);
FORCEPROP 1 LAST PATH I44
J 0
(-11997 2655);
DISPLAY 1.212766 (-11997 2655);
PAINT GREEN (-11997 2655);
DISPLAY INVISIBLE (-11997 2655);
FORCEADD RESISTOR..2
(-11850 3400);
FORCEPROP 1 LAST $LOCATION R166
J 0
(-11800 3250);
DISPLAY 1.212766 (-11800 3250);
PAINT GREEN (-11800 3250);
FORCEPROP 0 LAST CDS_LOCATION R166
J 0
(-11800 3550);
DISPLAY 1.021277 (-11800 3550);
DISPLAY INVISIBLE (-11800 3550);
FORCEPROP 0 LAST $SEC 1
J 0
(-11800 3550);
DISPLAY 0.680851 (-11800 3550);
PAINT MONO (-11800 3550);
DISPLAY INVISIBLE (-11800 3550);
FORCEPROP 0 LAST CDS_SEC 1
J 0
(-11800 3550);
DISPLAY 1.021277 (-11800 3550);
DISPLAY INVISIBLE (-11800 3550);
FORCEPROP 0 LASTPIN (-11850 3500) $PN 1
R 1
J 0
(-11860 3510);
DISPLAY 0.680851 (-11860 3510);
PAINT MONO (-11860 3510);
FORCEPROP 0 LASTPIN (-11850 3250) $PN 2
R 1
J 2
(-11860 3240);
DISPLAY 0.680851 (-11860 3240);
PAINT MONO (-11860 3240);
FORCEPROP 0 LAST PACKAGE 402
J 0
(-11800 3600);
DISPLAY 1.021277 (-11800 3600);
FORCEPROP 0 LAST NO_ASSY TRUE
J 0
(-11800 3350);
DISPLAY 0.808511 (-11800 3350);
DISPLAY BOTH (-11800 3350);
FORCEPROP 1 LAST VALUE 1.13KOHM
J 0
(-11800 3450);
DISPLAY 1.212766 (-11800 3450);
PAINT GREEN (-11800 3450);
FORCEPROP 1 LAST CDS_LMAN_SYM_OUTLINE -50,50,50,-100
J 0
(-11850 3400);
DISPLAY 0.468085 (-11850 3400);
PAINT GREEN (-11850 3400);
DISPLAY INVISIBLE (-11850 3400);
FORCEPROP 2 LAST CDS_LIB passive
J 0
(-11850 3400);
DISPLAY INVISIBLE (-11850 3400);
FORCEPROP 1 LAST CLS_PN G152-00055-01
J 0
(-11986 3600);
DISPLAY 1.212766 (-11986 3600);
PAINT GREEN (-11986 3600);
DISPLAY INVISIBLE (-11986 3600);
FORCEPROP 1 LAST TOLERANCE 1%
J 0
(-12047 3655);
DISPLAY 1.212766 (-12047 3655);
PAINT GREEN (-12047 3655);
DISPLAY INVISIBLE (-12047 3655);
FORCEPROP 1 LAST PATH I45
J 0
(-12047 3505);
DISPLAY 1.212766 (-12047 3505);
PAINT GREEN (-12047 3505);
DISPLAY INVISIBLE (-12047 3505);
FORCEADD CAPACITOR..2
(-11200 2600);
FORCEPROP 1 LAST $LOCATION C187
J 0
(-11100 2550);
DISPLAY 1.212766 (-11100 2550);
PAINT GREEN (-11100 2550);
FORCEPROP 0 LAST CDS_LOCATION C187
J 0
(-11100 2850);
DISPLAY 1.021277 (-11100 2850);
DISPLAY INVISIBLE (-11100 2850);
FORCEPROP 0 LAST $SEC 1
J 0
(-11100 2850);
DISPLAY 0.680851 (-11100 2850);
PAINT MONO (-11100 2850);
DISPLAY INVISIBLE (-11100 2850);
FORCEPROP 0 LAST CDS_SEC 1
J 0
(-11100 2850);
DISPLAY 1.021277 (-11100 2850);
DISPLAY INVISIBLE (-11100 2850);
FORCEPROP 0 LASTPIN (-11200 2700) $PN 1
R 1
J 0
(-11210 2710);
DISPLAY 0.680851 (-11210 2710);
PAINT MONO (-11210 2710);
FORCEPROP 0 LASTPIN (-11200 2450) $PN 2
R 1
J 2
(-11210 2440);
DISPLAY 0.680851 (-11210 2440);
PAINT MONO (-11210 2440);
FORCEPROP 0 LAST VOLTAGE 25V
J 0
(-11100 2650);
DISPLAY 1.021277 (-11100 2650);
FORCEPROP 1 LAST VALUE 0.1UF
J 0
(-11100 2450);
DISPLAY 1.212766 (-11100 2450);
PAINT GREEN (-11100 2450);
FORCEPROP 0 LAST PACKAGE 0402
J 0
(-11100 2350);
DISPLAY 1.021277 (-11100 2350);
FORCEPROP 1 LAST CLS_PN G105-0B104-EK
J 0
(-11300 2650);
DISPLAY 1.212766 (-11300 2650);
PAINT GREEN (-11300 2650);
DISPLAY INVISIBLE (-11300 2650);
FORCEPROP 2 LAST CDS_LIB passive
J 0
(-11200 2600);
DISPLAY INVISIBLE (-11200 2600);
FORCEPROP 1 LAST CDS_LMAN_SYM_OUTLINE -50,0,50,-50
J 0
(-11200 2600);
DISPLAY 0.468085 (-11200 2600);
PAINT GREEN (-11200 2600);
DISPLAY INVISIBLE (-11200 2600);
FORCEPROP 1 LAST TOLERANCE 10%
J 0
(-11350 2700);
DISPLAY 1.212766 (-11350 2700);
PAINT GREEN (-11350 2700);
DISPLAY INVISIBLE (-11350 2700);
FORCEPROP 1 LAST PATH I46
J 0
(-11300 2650);
DISPLAY 1.212766 (-11300 2650);
PAINT GREEN (-11300 2650);
DISPLAY INVISIBLE (-11300 2650);
FORCEADD CAPACITOR..2
(-11200 3550);
FORCEPROP 1 LAST $LOCATION C186
J 0
(-11100 3500);
DISPLAY 1.212766 (-11100 3500);
PAINT GREEN (-11100 3500);
FORCEPROP 2 LAST CDS_LOCATION C186
J 0
(-11100 3800);
DISPLAY 1.021277 (-11100 3800);
DISPLAY INVISIBLE (-11100 3800);
FORCEPROP 2 LAST $SEC 1
J 0
(-11100 3800);
DISPLAY 0.680851 (-11100 3800);
PAINT MONO (-11100 3800);
DISPLAY INVISIBLE (-11100 3800);
FORCEPROP 2 LAST CDS_SEC 1
J 0
(-11100 3800);
DISPLAY 1.021277 (-11100 3800);
DISPLAY INVISIBLE (-11100 3800);
FORCEPROP 2 LASTPIN (-11200 3650) $PN 1
R 1
J 0
(-11210 3660);
DISPLAY 0.680851 (-11210 3660);
PAINT MONO (-11210 3660);
FORCEPROP 2 LASTPIN (-11200 3400) $PN 2
R 1
J 2
(-11210 3390);
DISPLAY 0.680851 (-11210 3390);
PAINT MONO (-11210 3390);
FORCEPROP 0 LAST PACKAGE 0805
J 0
(-11100 3600);
DISPLAY 1.021277 (-11100 3600);
FORCEPROP 1 LAST VALUE 10UF
J 0
(-11100 3400);
DISPLAY 1.212766 (-11100 3400);
PAINT GREEN (-11100 3400);
FORCEPROP 0 LAST VOLTAGE 25V
J 0
(-11100 3700);
DISPLAY 1.021277 (-11100 3700);
FORCEPROP 1 LAST CDS_LMAN_SYM_OUTLINE -50,0,50,-50
J 0
(-11200 3550);
DISPLAY 0.468085 (-11200 3550);
PAINT GREEN (-11200 3550);
DISPLAY INVISIBLE (-11200 3550);
FORCEPROP 2 LAST CDS_LIB passive
J 0
(-11200 3550);
DISPLAY INVISIBLE (-11200 3550);
FORCEPROP 1 LAST TOLERANCE 20%
J 0
(-11350 3650);
DISPLAY 1.212766 (-11350 3650);
PAINT GREEN (-11350 3650);
DISPLAY INVISIBLE (-11350 3650);
FORCEPROP 1 LAST CLS_PN G107-0F106-EM
J 0
(-11300 3600);
DISPLAY 1.212766 (-11300 3600);
PAINT GREEN (-11300 3600);
DISPLAY INVISIBLE (-11300 3600);
FORCEPROP 1 LAST PATH I47
J 0
(-11300 3600);
DISPLAY 1.212766 (-11300 3600);
PAINT GREEN (-11300 3600);
DISPLAY INVISIBLE (-11300 3600);
FORCEADD GND_SG..1
(-10700 1950);
FORCEPROP 3 LASTPIN (-10650 2000) SIG_NAME SG\g
J 0
(-10640 2010);
DISPLAY 0.659574 (-10640 2010);
PAINT MONO (-10640 2010);
DISPLAY INVISIBLE (-10640 2010);
FORCEPROP 2 LAST VOLTAGE 0
J 0
(-10600 1900);
DISPLAY 1.021277 (-10600 1900);
FORCEPROP 1 LAST HDL_POWER SG
J 1
(-10645 1855);
DISPLAY 0.808511 (-10645 1855);
PAINT GREEN (-10645 1855);
FORCEPROP 1 LAST CDS_LMAN_SYM_OUTLINE 0,0,100,-50
J 0
(-10700 1950);
DISPLAY 0.468085 (-10700 1950);
PAINT GREEN (-10700 1950);
DISPLAY INVISIBLE (-10700 1950);
FORCEPROP 2 LAST CDS_LIB cls
J 0
(-10700 1950);
PAINT BLUE (-10700 1950);
DISPLAY INVISIBLE (-10700 1950);
FORCEPROP 1 LAST BODY_TYPE PLUMBING
J 0
(-10685 1935);
DISPLAY 0.808511 (-10685 1935);
PAINT GREEN (-10685 1935);
DISPLAY INVISIBLE (-10685 1935);
FORCEPROP 1 LAST PATH I48
J 0
(-10665 1950);
DISPLAY 0.808511 (-10665 1950);
PAINT GREEN (-10665 1950);
DISPLAY INVISIBLE (-10665 1950);
FORCEADD CAPACITOR..2
(-10650 2350);
FORCEPROP 1 LAST $LOCATION C191
J 0
(-10550 2200);
DISPLAY 1.212766 (-10550 2200);
PAINT GREEN (-10550 2200);
FORCEPROP 0 LAST CDS_LOCATION C191
J 0
(-10600 2350);
DISPLAY 1.212766 (-10600 2350);
PAINT GREEN (-10600 2350);
DISPLAY INVISIBLE (-10600 2350);
FORCEPROP 0 LAST $SEC 1
J 0
(-10600 2450);
DISPLAY 0.851064 (-10600 2450);
PAINT MONO (-10600 2450);
DISPLAY INVISIBLE (-10600 2450);
FORCEPROP 0 LAST CDS_SEC 1
J 0
(-10600 2450);
DISPLAY 0.851064 (-10600 2450);
DISPLAY INVISIBLE (-10600 2450);
FORCEPROP 0 LASTPIN (-10650 2450) $PN 1
R 1
J 0
(-10660 2460);
DISPLAY 0.851064 (-10660 2460);
PAINT MONO (-10660 2460);
FORCEPROP 0 LASTPIN (-10650 2200) $PN 2
R 1
J 2
(-10660 2190);
DISPLAY 0.851064 (-10660 2190);
PAINT MONO (-10660 2190);
FORCEPROP 0 LAST VOLTAGE 25V
J 0
(-10550 2500);
DISPLAY 1.021277 (-10550 2500);
FORCEPROP 0 LAST PACKAGE 0201
J 0
(-10550 2400);
DISPLAY 1.021277 (-10550 2400);
FORCEPROP 1 LAST VALUE 0.01UF
J 0
(-10550 2300);
DISPLAY 0.978723 (-10550 2300);
PAINT GREEN (-10550 2300);
FORCEPROP 1 LAST CLS_PN G104-0B103-EK
J 0
(-10750 2400);
DISPLAY 1.212766 (-10750 2400);
PAINT GREEN (-10750 2400);
DISPLAY INVISIBLE (-10750 2400);
FORCEPROP 1 LAST CDS_LMAN_SYM_OUTLINE -50,0,50,-50
J 0
(-10650 2350);
DISPLAY 0.468085 (-10650 2350);
PAINT GREEN (-10650 2350);
DISPLAY INVISIBLE (-10650 2350);
FORCEPROP 2 LAST CDS_LIB passive
J 0
(-10650 2350);
DISPLAY INVISIBLE (-10650 2350);
FORCEPROP 1 LAST TOLERANCE 10%
J 0
(-10800 2450);
DISPLAY 1.212766 (-10800 2450);
PAINT GREEN (-10800 2450);
DISPLAY INVISIBLE (-10800 2450);
FORCEPROP 1 LAST PATH I49
J 0
(-10750 2400);
DISPLAY 1.212766 (-10750 2400);
PAINT GREEN (-10750 2400);
DISPLAY INVISIBLE (-10750 2400);
FORCEADD CAPACITOR..2
(-10700 7250);
FORCEPROP 1 LAST $LOCATION C190
J 0
(-10600 7200);
DISPLAY 1.212766 (-10600 7200);
PAINT GREEN (-10600 7200);
FORCEPROP 0 LAST CDS_LOCATION C190
J 0
(-10650 7250);
DISPLAY 1.212766 (-10650 7250);
PAINT GREEN (-10650 7250);
DISPLAY INVISIBLE (-10650 7250);
FORCEPROP 0 LAST $SEC 1
J 0
(-10650 7350);
DISPLAY 0.851064 (-10650 7350);
PAINT MONO (-10650 7350);
DISPLAY INVISIBLE (-10650 7350);
FORCEPROP 0 LAST CDS_SEC 1
J 0
(-10650 7350);
DISPLAY 0.851064 (-10650 7350);
DISPLAY INVISIBLE (-10650 7350);
FORCEPROP 0 LASTPIN (-10700 7350) $PN 1
R 1
J 0
(-10710 7360);
DISPLAY 0.851064 (-10710 7360);
PAINT MONO (-10710 7360);
FORCEPROP 0 LASTPIN (-10700 7100) $PN 2
R 1
J 2
(-10710 7090);
DISPLAY 0.851064 (-10710 7090);
PAINT MONO (-10710 7090);
FORCEPROP 0 LAST VOLTAGE 25V
J 0
(-10600 7400);
DISPLAY 1.021277 (-10600 7400);
FORCEPROP 0 LAST PACKAGE 0201
J 0
(-10600 7100);
DISPLAY 1.021277 (-10600 7100);
FORCEPROP 1 LAST VALUE 0.01UF
J 0
(-10600 7300);
DISPLAY 0.978723 (-10600 7300);
PAINT GREEN (-10600 7300);
FORCEPROP 1 LAST CLS_PN G104-0B103-EK
J 0
(-10800 7300);
DISPLAY 1.212766 (-10800 7300);
PAINT GREEN (-10800 7300);
DISPLAY INVISIBLE (-10800 7300);
FORCEPROP 2 LAST CDS_LIB passive
J 0
(-10700 7250);
DISPLAY INVISIBLE (-10700 7250);
FORCEPROP 1 LAST CDS_LMAN_SYM_OUTLINE -50,0,50,-50
J 0
(-10700 7250);
DISPLAY 0.468085 (-10700 7250);
PAINT GREEN (-10700 7250);
DISPLAY INVISIBLE (-10700 7250);
FORCEPROP 1 LAST TOLERANCE 10%
J 0
(-10850 7350);
DISPLAY 1.212766 (-10850 7350);
PAINT GREEN (-10850 7350);
DISPLAY INVISIBLE (-10850 7350);
FORCEPROP 1 LAST PATH I5
J 0
(-10800 7300);
DISPLAY 1.212766 (-10800 7300);
PAINT GREEN (-10800 7300);
DISPLAY INVISIBLE (-10800 7300);
FORCEADD GND_SG..1
(-10800 3100);
FORCEPROP 3 LASTPIN (-10750 3150) SIG_NAME SG\g
J 0
(-10740 3160);
DISPLAY 0.659574 (-10740 3160);
PAINT MONO (-10740 3160);
DISPLAY INVISIBLE (-10740 3160);
FORCEPROP 2 LAST VOLTAGE 0
J 0
(-10700 3050);
DISPLAY 1.021277 (-10700 3050);
FORCEPROP 1 LAST HDL_POWER SG
J 1
(-10745 3005);
DISPLAY 0.808511 (-10745 3005);
PAINT GREEN (-10745 3005);
FORCEPROP 2 LAST CDS_LIB cls
J 0
(-10800 3100);
DISPLAY INVISIBLE (-10800 3100);
FORCEPROP 1 LAST CDS_LMAN_SYM_OUTLINE 0,0,100,-50
J 0
(-10800 3100);
DISPLAY 0.468085 (-10800 3100);
PAINT GREEN (-10800 3100);
DISPLAY INVISIBLE (-10800 3100);
FORCEPROP 1 LAST BODY_TYPE PLUMBING
J 0
(-10785 3085);
DISPLAY 0.808511 (-10785 3085);
PAINT GREEN (-10785 3085);
DISPLAY INVISIBLE (-10785 3085);
FORCEPROP 1 LAST PATH I50
J 0
(-10765 3100);
DISPLAY 0.808511 (-10765 3100);
PAINT GREEN (-10765 3100);
DISPLAY INVISIBLE (-10765 3100);
FORCEADD CAPACITOR..2
(-10750 3550);
FORCEPROP 1 LAST $LOCATION C189
J 0
(-10650 3600);
DISPLAY 1.212766 (-10650 3600);
PAINT GREEN (-10650 3600);
FORCEPROP 0 LAST CDS_LOCATION C189
J 0
(-10650 3800);
DISPLAY 1.021277 (-10650 3800);
DISPLAY INVISIBLE (-10650 3800);
FORCEPROP 0 LAST $SEC 1
J 0
(-10650 3800);
DISPLAY 0.680851 (-10650 3800);
PAINT MONO (-10650 3800);
DISPLAY INVISIBLE (-10650 3800);
FORCEPROP 0 LAST CDS_SEC 1
J 0
(-10650 3800);
DISPLAY 1.021277 (-10650 3800);
DISPLAY INVISIBLE (-10650 3800);
FORCEPROP 0 LASTPIN (-10750 3650) $PN 1
R 1
J 0
(-10760 3660);
DISPLAY 0.680851 (-10760 3660);
PAINT MONO (-10760 3660);
FORCEPROP 0 LASTPIN (-10750 3400) $PN 2
R 1
J 2
(-10760 3390);
DISPLAY 0.680851 (-10760 3390);
PAINT MONO (-10760 3390);
FORCEPROP 1 LAST VALUE 0.1UF
J 0
(-10650 3500);
DISPLAY 1.212766 (-10650 3500);
PAINT GREEN (-10650 3500);
FORCEPROP 0 LAST VOLTAGE 25V
J 0
(-10650 3700);
DISPLAY 1.021277 (-10650 3700);
FORCEPROP 0 LAST PACKAGE 0402
J 0
(-10650 3400);
DISPLAY 1.021277 (-10650 3400);
FORCEPROP 1 LAST CLS_PN G105-0B104-EK
J 0
(-10850 3600);
DISPLAY 1.212766 (-10850 3600);
PAINT GREEN (-10850 3600);
DISPLAY INVISIBLE (-10850 3600);
FORCEPROP 2 LAST CDS_LIB passive
J 0
(-10750 3550);
DISPLAY INVISIBLE (-10750 3550);
FORCEPROP 1 LAST CDS_LMAN_SYM_OUTLINE -50,0,50,-50
J 0
(-10750 3550);
DISPLAY 0.468085 (-10750 3550);
PAINT GREEN (-10750 3550);
DISPLAY INVISIBLE (-10750 3550);
FORCEPROP 1 LAST TOLERANCE 10%
J 0
(-10900 3650);
DISPLAY 1.212766 (-10900 3650);
PAINT GREEN (-10900 3650);
DISPLAY INVISIBLE (-10900 3650);
FORCEPROP 1 LAST PATH I51
J 0
(-10850 3600);
DISPLAY 1.212766 (-10850 3600);
PAINT GREEN (-10850 3600);
DISPLAY INVISIBLE (-10850 3600);
FORCEADD ISL80101IRAJZ_DFN10..1
(-9850 3450);
FORCEPROP 1 LAST $LOCATION U21
J 0
(-9850 3600);
DISPLAY 1.212766 (-9850 3600);
PAINT GREEN (-9850 3600);
FORCEPROP 0 LAST CDS_LOCATION U21
J 0
(-9800 3550);
DISPLAY 1.212766 (-9800 3550);
PAINT GREEN (-9800 3550);
DISPLAY INVISIBLE (-9800 3550);
FORCEPROP 2 LAST $SEC 1
J 0
(-9800 3750);
DISPLAY 0.680851 (-9800 3750);
PAINT MONO (-9800 3750);
DISPLAY INVISIBLE (-9800 3750);
FORCEPROP 2 LAST CDS_SEC 1
J 0
(-9800 3750);
DISPLAY 1.021277 (-9800 3750);
DISPLAY INVISIBLE (-9800 3750);
FORCEPROP 2 LASTPIN (-9950 2850) $PN 7
J 2
(-9960 2860);
DISPLAY 0.680851 (-9960 2860);
PAINT MONO (-9960 2860);
FORCEPROP 2 LASTPIN (-8850 2650) $PN 5
J 0
(-8840 2660);
DISPLAY 0.680851 (-8840 2660);
PAINT MONO (-8840 2660);
FORCEPROP 2 LASTPIN (-9950 3050) $PN 8
J 2
(-9960 3060);
DISPLAY 0.680851 (-9960 3060);
PAINT MONO (-9960 3060);
FORCEPROP 2 LASTPIN (-8850 2850) $PN 4
J 0
(-8840 2860);
DISPLAY 0.680851 (-8840 2860);
PAINT MONO (-8840 2860);
FORCEPROP 2 LASTPIN (-8850 3050) $PN 3
J 0
(-8840 3060);
DISPLAY 0.680851 (-8840 3060);
PAINT MONO (-8840 3060);
FORCEPROP 2 LASTPIN (-9950 2650) $PN 6
J 2
(-9960 2660);
DISPLAY 0.680851 (-9960 2660);
PAINT MONO (-9960 2660);
FORCEPROP 2 LASTPIN (-8850 2550) $PN 11
J 0
(-8840 2560);
DISPLAY 0.680851 (-8840 2560);
PAINT MONO (-8840 2560);
FORCEPROP 2 LASTPIN (-9950 3350) $PN 9
J 2
(-9960 3360);
DISPLAY 0.680851 (-9960 3360);
PAINT MONO (-9960 3360);
FORCEPROP 2 LASTPIN (-9950 3250) $PN 10
J 2
(-9960 3260);
DISPLAY 0.680851 (-9960 3260);
PAINT MONO (-9960 3260);
FORCEPROP 2 LASTPIN (-8850 3350) $PN 1
J 0
(-8840 3360);
DISPLAY 0.680851 (-8840 3360);
PAINT MONO (-8840 3360);
FORCEPROP 2 LASTPIN (-8850 3250) $PN 2
J 0
(-8840 3260);
DISPLAY 0.680851 (-8840 3260);
PAINT MONO (-8840 3260);
FORCEPROP 0 LAST PART_NUMBER ISL80101IRAJZ-T
J 0
(-9850 3750);
DISPLAY 1.021277 (-9850 3750);
FORCEPROP 1 LAST CLS_PN G222-10136-01
J 0
(-9850 3500);
DISPLAY 0.978723 (-9850 3500);
PAINT GREEN (-9850 3500);
FORCEPROP 1 LAST CDS_LMAN_SYM_OUTLINE 0,0,900,-1000
J 0
(-9850 3450);
DISPLAY 0.468085 (-9850 3450);
PAINT GREEN (-9850 3450);
DISPLAY INVISIBLE (-9850 3450);
FORCEPROP 2 LAST CDS_LIB analog
J 0
(-9850 3450);
PAINT BLUE (-9850 3450);
DISPLAY INVISIBLE (-9850 3450);
FORCEPROP 0 LAST CDS_PHYS_PART_NAME ISL80101IRAJZ_DFN10-G222-10136A
J 0
(-9800 3750);
DISPLAY INVISIBLE (-9800 3750);
FORCEPROP 1 LAST PATH I52
J 0
(-9800 3500);
DISPLAY 1.212766 (-9800 3500);
PAINT GREEN (-9800 3500);
DISPLAY INVISIBLE (-9800 3500);
FORCEADD RESISTOR..2
(-6400 8350);
FORCEPROP 1 LAST $LOCATION R185
J 0
(-6350 8350);
DISPLAY 1.212766 (-6350 8350);
PAINT GREEN (-6350 8350);
FORCEPROP 0 LAST CDS_LOCATION R185
J 0
(-6350 8200);
DISPLAY 1.212766 (-6350 8200);
PAINT GREEN (-6350 8200);
DISPLAY INVISIBLE (-6350 8200);
FORCEPROP 0 LAST $SEC 1
J 0
(-6350 8500);
DISPLAY 0.680851 (-6350 8500);
PAINT MONO (-6350 8500);
DISPLAY INVISIBLE (-6350 8500);
FORCEPROP 0 LAST CDS_SEC 1
J 0
(-6350 8500);
DISPLAY 1.021277 (-6350 8500);
DISPLAY INVISIBLE (-6350 8500);
FORCEPROP 0 LASTPIN (-6400 8450) $PN 1
R 1
J 0
(-6410 8410);
DISPLAY 0.680851 (-6410 8410);
PAINT MONO (-6410 8410);
FORCEPROP 0 LASTPIN (-6400 8200) $PN 2
R 1
J 2
(-6410 8190);
DISPLAY 0.680851 (-6410 8190);
PAINT MONO (-6410 8190);
FORCEPROP 1 LAST VALUE 4.22KOHM
J 0
(-6350 8300);
DISPLAY 0.978723 (-6350 8300);
PAINT GREEN (-6350 8300);
FORCEPROP 0 LAST PACKAGE 0402
J 0
(-6350 8500);
DISPLAY 1.021277 (-6350 8500);
FORCEPROP 1 LAST TOLERANCE 1%
J 0
(-6350 8250);
DISPLAY 0.978723 (-6350 8250);
PAINT GREEN (-6350 8250);
FORCEPROP 1 LAST CLS_PN G155-04221-01
J 0
(-6536 8550);
DISPLAY 1.212766 (-6536 8550);
PAINT GREEN (-6536 8550);
DISPLAY INVISIBLE (-6536 8550);
FORCEPROP 0 LAST CDS_PHYS_PART_NAME RESISTOR-G155-02871-01,2.87KOHB
J 0
(-6350 8500);
DISPLAY INVISIBLE (-6350 8500);
FORCEPROP 1 LAST CDS_LMAN_SYM_OUTLINE -50,50,50,-100
J 0
(-6400 8350);
DISPLAY 0.468085 (-6400 8350);
PAINT GREEN (-6400 8350);
DISPLAY INVISIBLE (-6400 8350);
FORCEPROP 2 LAST CDS_LIB passive
J 0
(-6400 8350);
DISPLAY INVISIBLE (-6400 8350);
FORCEPROP 1 LAST PATH I59
J 0
(-6597 8455);
DISPLAY 1.212766 (-6597 8455);
PAINT GREEN (-6597 8455);
DISPLAY INVISIBLE (-6597 8455);
FORCEADD ISL80101IRAJZ_DFN10..1
(-9900 8350);
FORCEPROP 1 LAST $LOCATION U20
J 0
(-9900 8500);
DISPLAY 1.212766 (-9900 8500);
PAINT GREEN (-9900 8500);
FORCEPROP 0 LAST CDS_LOCATION U20
J 0
(-9850 8450);
DISPLAY 1.212766 (-9850 8450);
PAINT GREEN (-9850 8450);
DISPLAY INVISIBLE (-9850 8450);
FORCEPROP 2 LAST $SEC 1
J 0
(-9850 8650);
DISPLAY 0.680851 (-9850 8650);
PAINT MONO (-9850 8650);
DISPLAY INVISIBLE (-9850 8650);
FORCEPROP 2 LAST CDS_SEC 1
J 0
(-9850 8650);
DISPLAY 1.021277 (-9850 8650);
DISPLAY INVISIBLE (-9850 8650);
FORCEPROP 2 LASTPIN (-10000 7750) $PN 7
J 2
(-10010 7760);
DISPLAY 0.680851 (-10010 7760);
PAINT MONO (-10010 7760);
FORCEPROP 2 LASTPIN (-8900 7550) $PN 5
J 0
(-8890 7560);
DISPLAY 0.680851 (-8890 7560);
PAINT MONO (-8890 7560);
FORCEPROP 2 LASTPIN (-10000 7950) $PN 8
J 2
(-10010 7960);
DISPLAY 0.680851 (-10010 7960);
PAINT MONO (-10010 7960);
FORCEPROP 2 LASTPIN (-8900 7750) $PN 4
J 0
(-8890 7760);
DISPLAY 0.680851 (-8890 7760);
PAINT MONO (-8890 7760);
FORCEPROP 2 LASTPIN (-8900 7950) $PN 3
J 0
(-8890 7960);
DISPLAY 0.680851 (-8890 7960);
PAINT MONO (-8890 7960);
FORCEPROP 2 LASTPIN (-10000 7550) $PN 6
J 2
(-10010 7560);
DISPLAY 0.680851 (-10010 7560);
PAINT MONO (-10010 7560);
FORCEPROP 2 LASTPIN (-8900 7450) $PN 11
J 0
(-8890 7460);
DISPLAY 0.680851 (-8890 7460);
PAINT MONO (-8890 7460);
FORCEPROP 2 LASTPIN (-10000 8250) $PN 9
J 2
(-10010 8260);
DISPLAY 0.680851 (-10010 8260);
PAINT MONO (-10010 8260);
FORCEPROP 2 LASTPIN (-10000 8150) $PN 10
J 2
(-10010 8160);
DISPLAY 0.680851 (-10010 8160);
PAINT MONO (-10010 8160);
FORCEPROP 2 LASTPIN (-8900 8250) $PN 1
J 0
(-8890 8260);
DISPLAY 0.680851 (-8890 8260);
PAINT MONO (-8890 8260);
FORCEPROP 2 LASTPIN (-8900 8150) $PN 2
J 0
(-8890 8160);
DISPLAY 0.680851 (-8890 8160);
PAINT MONO (-8890 8160);
FORCEPROP 1 LAST CLS_PN G222-10136-01
J 0
(-9900 8400);
DISPLAY 0.978723 (-9900 8400);
PAINT GREEN (-9900 8400);
FORCEPROP 0 LAST PART_NUMBER ISL80101IRAJZ-T
J 0
(-9900 8650);
DISPLAY 1.021277 (-9900 8650);
FORCEPROP 1 LAST CDS_LMAN_SYM_OUTLINE 0,0,900,-1000
J 0
(-9900 8350);
DISPLAY 0.468085 (-9900 8350);
PAINT GREEN (-9900 8350);
DISPLAY INVISIBLE (-9900 8350);
FORCEPROP 2 LAST CDS_LIB analog
J 0
(-9900 8350);
PAINT BLUE (-9900 8350);
DISPLAY INVISIBLE (-9900 8350);
FORCEPROP 0 LAST CDS_PHYS_PART_NAME ISL80101IRAJZ_DFN10-G222-10136A
J 0
(-9850 8650);
DISPLAY INVISIBLE (-9850 8650);
FORCEPROP 1 LAST PATH I6
J 0
(-9850 8400);
DISPLAY 1.212766 (-9850 8400);
PAINT GREEN (-9850 8400);
DISPLAY INVISIBLE (-9850 8400);
FORCEADD CAPACITOR..2
(-5750 8350);
FORCEPROP 1 LAST $LOCATION C194
J 0
(-5650 8250);
DISPLAY 1.212766 (-5650 8250);
PAINT GREEN (-5650 8250);
FORCEPROP 2 LAST CDS_LOCATION C194
J 0
(-5650 8600);
DISPLAY 1.021277 (-5650 8600);
DISPLAY INVISIBLE (-5650 8600);
FORCEPROP 2 LAST $SEC 1
J 0
(-5650 8600);
DISPLAY 0.680851 (-5650 8600);
PAINT MONO (-5650 8600);
DISPLAY INVISIBLE (-5650 8600);
FORCEPROP 2 LAST CDS_SEC 1
J 0
(-5650 8600);
DISPLAY 1.021277 (-5650 8600);
DISPLAY INVISIBLE (-5650 8600);
FORCEPROP 2 LASTPIN (-5750 8450) $PN 1
R 1
J 0
(-5760 8460);
DISPLAY 0.680851 (-5760 8460);
PAINT MONO (-5760 8460);
FORCEPROP 2 LASTPIN (-5750 8200) $PN 2
R 1
J 2
(-5760 8190);
DISPLAY 0.680851 (-5760 8190);
PAINT MONO (-5760 8190);
FORCEPROP 1 LAST VALUE 10UF
J 0
(-5650 8150);
DISPLAY 1.212766 (-5650 8150);
PAINT GREEN (-5650 8150);
FORCEPROP 0 LAST VOLTAGE 25V
J 0
(-5650 8500);
DISPLAY 1.021277 (-5650 8500);
FORCEPROP 0 LAST PACKAGE 0805
J 0
(-5650 8400);
DISPLAY 1.021277 (-5650 8400);
FORCEPROP 1 LAST CDS_LMAN_SYM_OUTLINE -50,0,50,-50
J 0
(-5750 8350);
DISPLAY 0.468085 (-5750 8350);
PAINT GREEN (-5750 8350);
DISPLAY INVISIBLE (-5750 8350);
FORCEPROP 2 LAST CDS_LIB passive
J 0
(-5750 8350);
DISPLAY INVISIBLE (-5750 8350);
FORCEPROP 1 LAST TOLERANCE 20%
J 0
(-5900 8450);
DISPLAY 1.212766 (-5900 8450);
PAINT GREEN (-5900 8450);
DISPLAY INVISIBLE (-5900 8450);
FORCEPROP 1 LAST CLS_PN G107-0F106-EM
J 0
(-5850 8400);
DISPLAY 1.212766 (-5850 8400);
PAINT GREEN (-5850 8400);
DISPLAY INVISIBLE (-5850 8400);
FORCEPROP 1 LAST PATH I60
J 0
(-5850 8400);
DISPLAY 1.212766 (-5850 8400);
PAINT GREEN (-5850 8400);
DISPLAY INVISIBLE (-5850 8400);
FORCEADD CAPACITOR..2
(-5150 8350);
FORCEPROP 1 LAST $LOCATION C196
J 0
(-5050 8250);
DISPLAY 1.212766 (-5050 8250);
PAINT GREEN (-5050 8250);
FORCEPROP 0 LAST CDS_LOCATION C196
J 0
(-5050 8600);
DISPLAY 1.021277 (-5050 8600);
DISPLAY INVISIBLE (-5050 8600);
FORCEPROP 0 LAST $SEC 1
J 0
(-5050 8600);
DISPLAY 0.680851 (-5050 8600);
PAINT MONO (-5050 8600);
DISPLAY INVISIBLE (-5050 8600);
FORCEPROP 0 LAST CDS_SEC 1
J 0
(-5050 8600);
DISPLAY 1.021277 (-5050 8600);
DISPLAY INVISIBLE (-5050 8600);
FORCEPROP 0 LASTPIN (-5150 8450) $PN 1
R 1
J 0
(-5160 8460);
DISPLAY 0.680851 (-5160 8460);
PAINT MONO (-5160 8460);
FORCEPROP 0 LASTPIN (-5150 8200) $PN 2
R 1
J 2
(-5160 8190);
DISPLAY 0.680851 (-5160 8190);
PAINT MONO (-5160 8190);
FORCEPROP 0 LAST PACKAGE 0402
J 0
(-5050 8400);
DISPLAY 1.021277 (-5050 8400);
FORCEPROP 0 LAST VOLTAGE 25V
J 0
(-5050 8500);
DISPLAY 1.021277 (-5050 8500);
FORCEPROP 1 LAST VALUE 0.1UF
J 0
(-5050 8150);
DISPLAY 1.212766 (-5050 8150);
PAINT GREEN (-5050 8150);
FORCEPROP 1 LAST TOLERANCE 10%
J 0
(-5300 8450);
DISPLAY 1.212766 (-5300 8450);
PAINT GREEN (-5300 8450);
DISPLAY INVISIBLE (-5300 8450);
FORCEPROP 2 LAST CDS_LIB passive
J 0
(-5150 8350);
DISPLAY INVISIBLE (-5150 8350);
FORCEPROP 1 LAST CDS_LMAN_SYM_OUTLINE -50,0,50,-50
J 0
(-5150 8350);
DISPLAY 0.468085 (-5150 8350);
PAINT GREEN (-5150 8350);
DISPLAY INVISIBLE (-5150 8350);
FORCEPROP 1 LAST CLS_PN G105-0B104-EK
J 0
(-5250 8400);
DISPLAY 1.212766 (-5250 8400);
PAINT GREEN (-5250 8400);
DISPLAY INVISIBLE (-5250 8400);
FORCEPROP 1 LAST PATH I61
J 0
(-5250 8400);
DISPLAY 1.212766 (-5250 8400);
PAINT GREEN (-5250 8400);
DISPLAY INVISIBLE (-5250 8400);
FORCEADD GND_SG..1
(-8650 6700);
FORCEPROP 3 LASTPIN (-8600 6750) SIG_NAME SG\g
J 0
(-8590 6760);
DISPLAY 0.659574 (-8590 6760);
PAINT MONO (-8590 6760);
DISPLAY INVISIBLE (-8590 6760);
FORCEPROP 2 LAST VOLTAGE 0
J 0
(-8550 6650);
DISPLAY 1.021277 (-8550 6650);
FORCEPROP 1 LAST HDL_POWER SG
J 1
(-8595 6605);
DISPLAY 0.808511 (-8595 6605);
PAINT GREEN (-8595 6605);
FORCEPROP 1 LAST CDS_LMAN_SYM_OUTLINE 0,0,100,-50
J 0
(-8650 6700);
DISPLAY 0.468085 (-8650 6700);
PAINT GREEN (-8650 6700);
DISPLAY INVISIBLE (-8650 6700);
FORCEPROP 2 LAST CDS_LIB cls
J 0
(-8650 6700);
PAINT BLUE (-8650 6700);
DISPLAY INVISIBLE (-8650 6700);
FORCEPROP 1 LAST BODY_TYPE PLUMBING
J 0
(-8635 6685);
DISPLAY 0.808511 (-8635 6685);
PAINT GREEN (-8635 6685);
DISPLAY INVISIBLE (-8635 6685);
FORCEPROP 1 LAST PATH I7
J 0
(-8615 6700);
DISPLAY 0.808511 (-8615 6700);
PAINT GREEN (-8615 6700);
DISPLAY INVISIBLE (-8615 6700);
FORCEADD GND_SG..1
(-8600 1800);
FORCEPROP 3 LASTPIN (-8550 1850) SIG_NAME SG\g
J 0
(-8540 1860);
DISPLAY 0.659574 (-8540 1860);
PAINT MONO (-8540 1860);
DISPLAY INVISIBLE (-8540 1860);
FORCEPROP 2 LAST VOLTAGE 0
J 0
(-8500 1750);
DISPLAY 1.021277 (-8500 1750);
FORCEPROP 1 LAST HDL_POWER SG
J 1
(-8545 1705);
DISPLAY 0.808511 (-8545 1705);
PAINT GREEN (-8545 1705);
FORCEPROP 2 LAST CDS_LIB cls
J 0
(-8600 1800);
PAINT BLUE (-8600 1800);
DISPLAY INVISIBLE (-8600 1800);
FORCEPROP 1 LAST CDS_LMAN_SYM_OUTLINE 0,0,100,-50
J 0
(-8600 1800);
DISPLAY 0.468085 (-8600 1800);
PAINT GREEN (-8600 1800);
DISPLAY INVISIBLE (-8600 1800);
FORCEPROP 1 LAST BODY_TYPE PLUMBING
J 0
(-8585 1785);
DISPLAY 0.808511 (-8585 1785);
PAINT GREEN (-8585 1785);
DISPLAY INVISIBLE (-8585 1785);
FORCEPROP 1 LAST PATH I70
J 0
(-8565 1800);
DISPLAY 0.808511 (-8565 1800);
PAINT GREEN (-8565 1800);
DISPLAY INVISIBLE (-8565 1800);
FORCEADD CAPACITOR..2
(-7650 1900);
FORCEPROP 1 LAST $LOCATION C193
J 0
(-7500 1900);
DISPLAY 1.212766 (-7500 1900);
PAINT GREEN (-7500 1900);
FORCEPROP 0 LAST CDS_LOCATION C193
J 0
(-7600 2100);
DISPLAY 1.021277 (-7600 2100);
DISPLAY INVISIBLE (-7600 2100);
FORCEPROP 0 LAST $SEC 1
J 0
(-7600 2100);
DISPLAY 0.680851 (-7600 2100);
PAINT MONO (-7600 2100);
DISPLAY INVISIBLE (-7600 2100);
FORCEPROP 0 LAST CDS_SEC 1
J 0
(-7600 2100);
DISPLAY 1.021277 (-7600 2100);
DISPLAY INVISIBLE (-7600 2100);
FORCEPROP 0 LASTPIN (-7650 2000) $PN 1
R 1
J 0
(-7660 2010);
DISPLAY 0.680851 (-7660 2010);
PAINT MONO (-7660 2010);
FORCEPROP 0 LASTPIN (-7650 1750) $PN 2
R 1
J 2
(-7660 1740);
DISPLAY 0.680851 (-7660 1740);
PAINT MONO (-7660 1740);
FORCEPROP 0 LAST VOLTAGE 25V
J 0
(-7500 2000);
DISPLAY 1.021277 (-7500 2000);
FORCEPROP 0 LAST PACKAGE 0201
J 0
(-7500 1700);
DISPLAY 1.021277 (-7500 1700);
FORCEPROP 1 LAST VALUE 0.01UF
J 0
(-7500 1800);
DISPLAY 0.978723 (-7500 1800);
PAINT GREEN (-7500 1800);
FORCEPROP 1 LAST CLS_PN G104-0B103-EK
J 0
(-7750 1950);
DISPLAY 1.212766 (-7750 1950);
PAINT GREEN (-7750 1950);
DISPLAY INVISIBLE (-7750 1950);
FORCEPROP 1 LAST TOLERANCE 10%
J 0
(-7800 2000);
DISPLAY 1.212766 (-7800 2000);
PAINT GREEN (-7800 2000);
DISPLAY INVISIBLE (-7800 2000);
FORCEPROP 2 LAST CDS_LIB passive
J 0
(-7650 1900);
DISPLAY INVISIBLE (-7650 1900);
FORCEPROP 1 LAST CDS_LMAN_SYM_OUTLINE -50,0,50,-50
J 0
(-7650 1900);
DISPLAY 0.468085 (-7650 1900);
PAINT GREEN (-7650 1900);
DISPLAY INVISIBLE (-7650 1900);
FORCEPROP 1 LAST PATH I71
J 0
(-7750 1950);
DISPLAY 1.212766 (-7750 1950);
PAINT GREEN (-7750 1950);
DISPLAY INVISIBLE (-7750 1950);
FORCEADD GND_SG..1
(-7700 1650);
FORCEPROP 3 LASTPIN (-7650 1700) SIG_NAME SG\g
J 0
(-7640 1710);
DISPLAY 0.659574 (-7640 1710);
PAINT MONO (-7640 1710);
DISPLAY INVISIBLE (-7640 1710);
FORCEPROP 2 LAST VOLTAGE 0
J 0
(-7600 1600);
DISPLAY 1.021277 (-7600 1600);
FORCEPROP 1 LAST HDL_POWER SG
J 1
(-7645 1555);
DISPLAY 0.808511 (-7645 1555);
PAINT GREEN (-7645 1555);
FORCEPROP 1 LAST CDS_LMAN_SYM_OUTLINE 0,0,100,-50
J 0
(-7700 1650);
DISPLAY 0.468085 (-7700 1650);
PAINT GREEN (-7700 1650);
DISPLAY INVISIBLE (-7700 1650);
FORCEPROP 2 LAST CDS_LIB cls
J 0
(-7700 1650);
DISPLAY INVISIBLE (-7700 1650);
FORCEPROP 1 LAST BODY_TYPE PLUMBING
J 0
(-7685 1635);
DISPLAY 0.808511 (-7685 1635);
PAINT GREEN (-7685 1635);
DISPLAY INVISIBLE (-7685 1635);
FORCEPROP 1 LAST PATH I72
J 0
(-7665 1650);
DISPLAY 0.808511 (-7665 1650);
PAINT GREEN (-7665 1650);
DISPLAY INVISIBLE (-7665 1650);
FORCEADD RESISTOR..2
(-7600 2400);
FORCEPROP 1 LAST $LOCATION R179
J 0
(-7550 2250);
DISPLAY 1.212766 (-7550 2250);
PAINT GREEN (-7550 2250);
FORCEPROP 2 LAST CDS_LOCATION R179
J 0
(-7750 2600);
DISPLAY 1.021277 (-7750 2600);
DISPLAY INVISIBLE (-7750 2600);
FORCEPROP 2 LAST $SEC 1
J 0
(-7750 2600);
DISPLAY 0.680851 (-7750 2600);
PAINT MONO (-7750 2600);
DISPLAY INVISIBLE (-7750 2600);
FORCEPROP 2 LAST CDS_SEC 1
J 0
(-7750 2600);
DISPLAY 1.021277 (-7750 2600);
DISPLAY INVISIBLE (-7750 2600);
FORCEPROP 2 LASTPIN (-7600 2500) $PN 1
R 1
J 0
(-7610 2510);
DISPLAY 0.680851 (-7610 2510);
PAINT MONO (-7610 2510);
FORCEPROP 2 LASTPIN (-7600 2250) $PN 2
R 1
J 2
(-7610 2240);
DISPLAY 0.680851 (-7610 2240);
PAINT MONO (-7610 2240);
FORCEPROP 1 LAST VALUE 4.7KOHM
J 0
(-7550 2350);
DISPLAY 1.212766 (-7550 2350);
PAINT GREEN (-7550 2350);
FORCEPROP 0 LAST PACKAGE 0402
J 0
(-7550 2500);
DISPLAY 1.021277 (-7550 2500);
FORCEPROP 1 LAST CDS_LMAN_SYM_OUTLINE -50,50,50,-100
J 0
(-7600 2400);
DISPLAY 0.468085 (-7600 2400);
PAINT GREEN (-7600 2400);
DISPLAY INVISIBLE (-7600 2400);
FORCEPROP 2 LAST CDS_LIB passive
J 0
(-7600 2400);
DISPLAY INVISIBLE (-7600 2400);
FORCEPROP 1 LAST CLS_PN G155-14701-01
J 0
(-7350 2450);
DISPLAY 1.212766 (-7350 2450);
PAINT GREEN (-7350 2450);
DISPLAY INVISIBLE (-7350 2450);
FORCEPROP 1 LAST TOLERANCE 1%
J 0
(-7350 2250);
DISPLAY 1.212766 (-7350 2250);
PAINT GREEN (-7350 2250);
DISPLAY INVISIBLE (-7350 2250);
FORCEPROP 1 LAST PATH I73
J 0
(-7797 2505);
DISPLAY 1.212766 (-7797 2505);
PAINT GREEN (-7797 2505);
DISPLAY INVISIBLE (-7797 2505);
FORCEADD RESISTOR..1
(-7000 2100);
FORCEPROP 1 LAST $LOCATION R182
J 2
(-7001 2155);
DISPLAY 1.212766 (-7001 2155);
PAINT GREEN (-7001 2155);
FORCEPROP 2 LAST CDS_LOCATION R182
J 0
(-7150 2300);
DISPLAY 1.021277 (-7150 2300);
DISPLAY INVISIBLE (-7150 2300);
FORCEPROP 2 LAST $SEC 1
J 0
(-7150 2300);
DISPLAY 0.680851 (-7150 2300);
PAINT MONO (-7150 2300);
DISPLAY INVISIBLE (-7150 2300);
FORCEPROP 2 LAST CDS_SEC 1
J 0
(-7150 2300);
DISPLAY 1.021277 (-7150 2300);
DISPLAY INVISIBLE (-7150 2300);
FORCEPROP 2 LASTPIN (-7100 2100) $PN 1
J 2
(-7110 2110);
DISPLAY 0.680851 (-7110 2110);
PAINT MONO (-7110 2110);
FORCEPROP 2 LASTPIN (-6850 2100) $PN 2
J 0
(-6840 2110);
DISPLAY 0.680851 (-6840 2110);
PAINT MONO (-6840 2110);
FORCEPROP 1 LAST VALUE 0OHM
J 0
(-6961 2155);
DISPLAY 1.212766 (-6961 2155);
PAINT GREEN (-6961 2155);
FORCEPROP 0 LAST PACKAGE 0402
J 0
(-7050 2000);
DISPLAY 1.021277 (-7050 2000);
FORCEPROP 2 LAST CDS_LIB passive
J 0
(-7000 2100);
DISPLAY INVISIBLE (-7000 2100);
FORCEPROP 1 LAST CDS_LMAN_SYM_OUTLINE -50,50,100,-50
J 0
(-7000 2100);
DISPLAY 0.468085 (-7000 2100);
PAINT GREEN (-7000 2100);
DISPLAY INVISIBLE (-7000 2100);
FORCEPROP 1 LAST CLS_PN G155-100R0-J0
J 0
(-7136 2300);
DISPLAY 1.212766 (-7136 2300);
PAINT GREEN (-7136 2300);
DISPLAY INVISIBLE (-7136 2300);
FORCEPROP 1 LAST TOLERANCE -
J 0
(-7197 2355);
DISPLAY 1.212766 (-7197 2355);
PAINT GREEN (-7197 2355);
DISPLAY INVISIBLE (-7197 2355);
FORCEPROP 1 LAST PATH I74
J 0
(-7197 2205);
DISPLAY 1.212766 (-7197 2205);
PAINT GREEN (-7197 2205);
DISPLAY INVISIBLE (-7197 2205);
FORCEADD VCC..1
(-7650 2650);
FORCEPROP 3 LASTPIN (-7600 2600) SIG_NAME XP3R3V\g
J 0
(-7590 2610);
DISPLAY 0.659574 (-7590 2610);
PAINT MONO (-7590 2610);
DISPLAY INVISIBLE (-7590 2610);
FORCEPROP 1 LAST HDL_POWER XP3R3V
J 1
(-7595 2705);
DISPLAY 1.021277 (-7595 2705);
PAINT GREEN (-7595 2705);
FORCEPROP 0 LAST VOLTAGE 3.3
J 0
(-7850 2750);
DISPLAY 1.021277 (-7850 2750);
DISPLAY BOTH (-7850 2750);
FORCEPROP 1 LAST CDS_LMAN_SYM_OUTLINE -250,250,250,-250
J 0
(-7650 2650);
DISPLAY 0.468085 (-7650 2650);
PAINT GREEN (-7650 2650);
DISPLAY INVISIBLE (-7650 2650);
FORCEPROP 2 LAST CDS_LIB cls
J 0
(-7650 2650);
DISPLAY INVISIBLE (-7650 2650);
FORCEPROP 1 LAST BODY_TYPE PLUMBING
J 0
(-7695 2607);
DISPLAY 0.340426 (-7695 2607);
PAINT GREEN (-7695 2607);
DISPLAY INVISIBLE (-7695 2607);
FORCEPROP 1 LAST PATH I75
J 0
(-7615 2740);
DISPLAY 0.808511 (-7615 2740);
PAINT GREEN (-7615 2740);
DISPLAY INVISIBLE (-7615 2740);
FORCEADD GND_SG..1
(-6100 2400);
FORCEPROP 3 LASTPIN (-6050 2450) SIG_NAME SG\g
J 0
(-6040 2460);
DISPLAY 0.659574 (-6040 2460);
PAINT MONO (-6040 2460);
DISPLAY INVISIBLE (-6040 2460);
FORCEPROP 1 LAST HDL_POWER SG
J 1
(-6050 2300);
DISPLAY 0.808511 (-6050 2300);
PAINT GREEN (-6050 2300);
FORCEPROP 2 LAST CDS_LIB cls
J 0
(-6100 2400);
DISPLAY INVISIBLE (-6100 2400);
FORCEPROP 1 LAST CDS_LMAN_SYM_OUTLINE 0,0,100,-50
J 0
(-6100 2400);
DISPLAY 0.468085 (-6100 2400);
PAINT GREEN (-6100 2400);
DISPLAY INVISIBLE (-6100 2400);
FORCEPROP 1 LAST BODY_TYPE PLUMBING
J 0
(-6085 2385);
DISPLAY 0.808511 (-6085 2385);
PAINT GREEN (-6085 2385);
DISPLAY INVISIBLE (-6085 2385);
FORCEPROP 1 LAST PATH I77
J 0
(-6065 2400);
DISPLAY 0.808511 (-6065 2400);
PAINT GREEN (-6065 2400);
DISPLAY INVISIBLE (-6065 2400);
FORCEADD RESISTOR..2
(-6350 3450);
FORCEPROP 1 LAST $LOCATION R187
J 0
(-6300 3450);
DISPLAY 1.212766 (-6300 3450);
PAINT GREEN (-6300 3450);
FORCEPROP 0 LAST CDS_LOCATION R187
J 0
(-6300 3300);
DISPLAY 1.212766 (-6300 3300);
PAINT GREEN (-6300 3300);
DISPLAY INVISIBLE (-6300 3300);
FORCEPROP 0 LAST $SEC 1
J 0
(-6300 3600);
DISPLAY 0.680851 (-6300 3600);
PAINT MONO (-6300 3600);
DISPLAY INVISIBLE (-6300 3600);
FORCEPROP 0 LAST CDS_SEC 1
J 0
(-6300 3600);
DISPLAY 1.021277 (-6300 3600);
DISPLAY INVISIBLE (-6300 3600);
FORCEPROP 0 LASTPIN (-6350 3550) $PN 1
R 1
J 0
(-6360 3510);
DISPLAY 0.680851 (-6360 3510);
PAINT MONO (-6360 3510);
FORCEPROP 0 LASTPIN (-6350 3300) $PN 2
R 1
J 2
(-6360 3290);
DISPLAY 0.680851 (-6360 3290);
PAINT MONO (-6360 3290);
FORCEPROP 1 LAST VALUE 4.22KOHM
J 0
(-6300 3400);
DISPLAY 0.978723 (-6300 3400);
PAINT GREEN (-6300 3400);
FORCEPROP 0 LAST PACKAGE 0402
J 0
(-6300 3600);
DISPLAY 1.021277 (-6300 3600);
FORCEPROP 1 LAST TOLERANCE 1%
J 0
(-6300 3350);
DISPLAY 0.978723 (-6300 3350);
PAINT GREEN (-6300 3350);
FORCEPROP 2 LAST CDS_LIB passive
J 0
(-6350 3450);
DISPLAY INVISIBLE (-6350 3450);
FORCEPROP 1 LAST CDS_LMAN_SYM_OUTLINE -50,50,50,-100
J 0
(-6350 3450);
DISPLAY 0.468085 (-6350 3450);
PAINT GREEN (-6350 3450);
DISPLAY INVISIBLE (-6350 3450);
FORCEPROP 0 LAST CDS_PHYS_PART_NAME RESISTOR-G155-02871-01,2.87KOHB
J 0
(-6300 3600);
DISPLAY INVISIBLE (-6300 3600);
FORCEPROP 1 LAST CLS_PN G155-04221-01
J 0
(-6486 3650);
DISPLAY 1.212766 (-6486 3650);
PAINT GREEN (-6486 3650);
DISPLAY INVISIBLE (-6486 3650);
FORCEPROP 1 LAST PATH I78
J 0
(-6547 3555);
DISPLAY 1.212766 (-6547 3555);
PAINT GREEN (-6547 3555);
DISPLAY INVISIBLE (-6547 3555);
FORCEADD RESISTOR..1
R 1
(-6300 2750);
FORCEPROP 1 LAST $LOCATION R188
R 1
J 2
(-6355 2849);
DISPLAY 1.212766 (-6355 2849);
PAINT GREEN (-6355 2849);
FORCEPROP 0 LAST CDS_LOCATION R188
R 1
J 0
(-6250 2950);
DISPLAY 1.021277 (-6250 2950);
DISPLAY INVISIBLE (-6250 2950);
FORCEPROP 0 LAST $SEC 1
R 1
J 0
(-6250 2950);
DISPLAY 0.680851 (-6250 2950);
PAINT MONO (-6250 2950);
DISPLAY INVISIBLE (-6250 2950);
FORCEPROP 0 LAST CDS_SEC 1
R 1
J 0
(-6250 2950);
DISPLAY 1.021277 (-6250 2950);
DISPLAY INVISIBLE (-6250 2950);
FORCEPROP 0 LASTPIN (-6300 2650) $PN 1
R 1
J 2
(-6310 2640);
DISPLAY 0.680851 (-6310 2640);
PAINT MONO (-6310 2640);
FORCEPROP 0 LASTPIN (-6300 2900) $PN 2
R 1
J 0
(-6310 2910);
DISPLAY 0.680851 (-6310 2910);
PAINT MONO (-6310 2910);
FORCEPROP 0 LAST PACKAGE 0402
R 1
J 0
(-6450 2700);
DISPLAY 1.021277 (-6450 2700);
FORCEPROP 1 LAST VALUE 3.24KOHM
R 1
J 0
(-6205 2539);
DISPLAY 1.212766 (-6205 2539);
PAINT GREEN (-6205 2539);
FORCEPROP 1 LAST CDS_LMAN_SYM_OUTLINE -50,50,100,-50
R 1
J 0
(-6300 2750);
DISPLAY 0.468085 (-6300 2750);
PAINT GREEN (-6300 2750);
DISPLAY INVISIBLE (-6300 2750);
FORCEPROP 2 LAST CDS_LIB passive
R 1
J 0
(-6300 2750);
DISPLAY INVISIBLE (-6300 2750);
FORCEPROP 1 LAST CLS_PN G155-03241-01
R 1
J 0
(-6500 2614);
DISPLAY 1.212766 (-6500 2614);
PAINT GREEN (-6500 2614);
DISPLAY INVISIBLE (-6500 2614);
FORCEPROP 1 LAST TOLERANCE 1%
R 1
J 0
(-6555 2553);
DISPLAY 1.212766 (-6555 2553);
PAINT GREEN (-6555 2553);
DISPLAY INVISIBLE (-6555 2553);
FORCEPROP 1 LAST PATH I79
R 1
J 0
(-6405 2553);
DISPLAY 1.212766 (-6405 2553);
PAINT GREEN (-6405 2553);
DISPLAY INVISIBLE (-6405 2553);
FORCEADD GND_SG..1
(-7700 6550);
FORCEPROP 3 LASTPIN (-7650 6600) SIG_NAME SG\g
J 0
(-7640 6610);
DISPLAY 0.659574 (-7640 6610);
PAINT MONO (-7640 6610);
DISPLAY INVISIBLE (-7640 6610);
FORCEPROP 2 LAST VOLTAGE 0
J 0
(-7600 6500);
DISPLAY 1.021277 (-7600 6500);
FORCEPROP 1 LAST HDL_POWER SG
J 1
(-7645 6455);
DISPLAY 0.808511 (-7645 6455);
PAINT GREEN (-7645 6455);
FORCEPROP 2 LAST CDS_LIB cls
J 0
(-7700 6550);
DISPLAY INVISIBLE (-7700 6550);
FORCEPROP 1 LAST CDS_LMAN_SYM_OUTLINE 0,0,100,-50
J 0
(-7700 6550);
DISPLAY 0.468085 (-7700 6550);
PAINT GREEN (-7700 6550);
DISPLAY INVISIBLE (-7700 6550);
FORCEPROP 1 LAST BODY_TYPE PLUMBING
J 0
(-7685 6535);
DISPLAY 0.808511 (-7685 6535);
PAINT GREEN (-7685 6535);
DISPLAY INVISIBLE (-7685 6535);
FORCEPROP 1 LAST PATH I8
J 0
(-7665 6550);
DISPLAY 0.808511 (-7665 6550);
PAINT GREEN (-7665 6550);
DISPLAY INVISIBLE (-7665 6550);
FORCEADD RESISTOR..1
R 1
(-6050 2750);
FORCEPROP 1 LAST $LOCATION R190
R 1
J 2
(-6105 2849);
DISPLAY 1.212766 (-6105 2849);
PAINT GREEN (-6105 2849);
FORCEPROP 0 LAST CDS_LOCATION R190
R 1
J 0
(-6000 2950);
DISPLAY 1.021277 (-6000 2950);
DISPLAY INVISIBLE (-6000 2950);
FORCEPROP 0 LAST $SEC 1
R 1
J 0
(-6000 2950);
DISPLAY 0.680851 (-6000 2950);
PAINT MONO (-6000 2950);
DISPLAY INVISIBLE (-6000 2950);
FORCEPROP 0 LAST CDS_SEC 1
R 1
J 0
(-6000 2950);
DISPLAY 1.021277 (-6000 2950);
DISPLAY INVISIBLE (-6000 2950);
FORCEPROP 0 LASTPIN (-6050 2650) $PN 1
R 1
J 2
(-6060 2640);
DISPLAY 0.680851 (-6060 2640);
PAINT MONO (-6060 2640);
FORCEPROP 0 LASTPIN (-6050 2900) $PN 2
R 1
J 0
(-6060 2910);
DISPLAY 0.680851 (-6060 2910);
PAINT MONO (-6060 2910);
FORCEPROP 0 LAST PACKAGE 0402
R 1
J 0
(-5850 2650);
DISPLAY 1.021277 (-5850 2650);
FORCEPROP 1 LAST VALUE 3.24KOHM
R 1
J 0
(-5955 2539);
DISPLAY 1.212766 (-5955 2539);
PAINT GREEN (-5955 2539);
FORCEPROP 2 LAST CDS_LIB passive
J 0
(-6050 2750);
DISPLAY INVISIBLE (-6050 2750);
FORCEPROP 1 LAST CDS_LMAN_SYM_OUTLINE -50,50,100,-50
R 1
J 0
(-6050 2750);
DISPLAY 0.468085 (-6050 2750);
PAINT GREEN (-6050 2750);
DISPLAY INVISIBLE (-6050 2750);
FORCEPROP 1 LAST CLS_PN G155-03241-01
R 1
J 0
(-6250 2614);
DISPLAY 1.212766 (-6250 2614);
PAINT GREEN (-6250 2614);
DISPLAY INVISIBLE (-6250 2614);
FORCEPROP 1 LAST TOLERANCE 1%
R 1
J 0
(-6305 2553);
DISPLAY 1.212766 (-6305 2553);
PAINT GREEN (-6305 2553);
DISPLAY INVISIBLE (-6305 2553);
FORCEPROP 1 LAST PATH I80
R 1
J 0
(-6155 2553);
DISPLAY 1.212766 (-6155 2553);
PAINT GREEN (-6155 2553);
DISPLAY INVISIBLE (-6155 2553);
FORCEADD CAPACITOR..2
(-5700 3450);
FORCEPROP 1 LAST $LOCATION C195
J 0
(-5600 3450);
DISPLAY 1.212766 (-5600 3450);
PAINT GREEN (-5600 3450);
FORCEPROP 2 LAST CDS_LOCATION C195
J 0
(-5600 3700);
DISPLAY 1.021277 (-5600 3700);
DISPLAY INVISIBLE (-5600 3700);
FORCEPROP 2 LAST $SEC 1
J 0
(-5600 3700);
DISPLAY 0.680851 (-5600 3700);
PAINT MONO (-5600 3700);
DISPLAY INVISIBLE (-5600 3700);
FORCEPROP 2 LAST CDS_SEC 1
J 0
(-5600 3700);
DISPLAY 1.021277 (-5600 3700);
DISPLAY INVISIBLE (-5600 3700);
FORCEPROP 2 LASTPIN (-5700 3550) $PN 1
R 1
J 0
(-5710 3560);
DISPLAY 0.680851 (-5710 3560);
PAINT MONO (-5710 3560);
FORCEPROP 2 LASTPIN (-5700 3300) $PN 2
R 1
J 2
(-5710 3290);
DISPLAY 0.680851 (-5710 3290);
PAINT MONO (-5710 3290);
FORCEPROP 0 LAST VOLTAGE 25V
J 0
(-5600 3650);
DISPLAY 1.021277 (-5600 3650);
FORCEPROP 0 LAST PACKAGE 0805
J 0
(-5600 3550);
DISPLAY 1.021277 (-5600 3550);
FORCEPROP 1 LAST VALUE 10UF
J 0
(-5600 3350);
DISPLAY 1.212766 (-5600 3350);
PAINT GREEN (-5600 3350);
FORCEPROP 2 LAST CDS_LIB passive
J 0
(-5700 3450);
DISPLAY INVISIBLE (-5700 3450);
FORCEPROP 1 LAST CDS_LMAN_SYM_OUTLINE -50,0,50,-50
J 0
(-5700 3450);
DISPLAY 0.468085 (-5700 3450);
PAINT GREEN (-5700 3450);
DISPLAY INVISIBLE (-5700 3450);
FORCEPROP 1 LAST TOLERANCE 20%
J 0
(-5850 3550);
DISPLAY 1.212766 (-5850 3550);
PAINT GREEN (-5850 3550);
DISPLAY INVISIBLE (-5850 3550);
FORCEPROP 1 LAST CLS_PN G107-0F106-EM
J 0
(-5800 3500);
DISPLAY 1.212766 (-5800 3500);
PAINT GREEN (-5800 3500);
DISPLAY INVISIBLE (-5800 3500);
FORCEPROP 1 LAST PATH I81
J 0
(-5800 3500);
DISPLAY 1.212766 (-5800 3500);
PAINT GREEN (-5800 3500);
DISPLAY INVISIBLE (-5800 3500);
FORCEADD GND_SG..1
(-5150 2900);
FORCEPROP 3 LASTPIN (-5100 2950) SIG_NAME SG\g
J 0
(-5090 2960);
DISPLAY 0.659574 (-5090 2960);
PAINT MONO (-5090 2960);
DISPLAY INVISIBLE (-5090 2960);
FORCEPROP 1 LAST HDL_POWER SG
J 1
(-5100 2750);
DISPLAY 0.808511 (-5100 2750);
PAINT GREEN (-5100 2750);
FORCEPROP 2 LAST CDS_LIB cls
J 0
(-5150 2900);
DISPLAY INVISIBLE (-5150 2900);
FORCEPROP 1 LAST CDS_LMAN_SYM_OUTLINE 0,0,100,-50
J 0
(-5150 2900);
DISPLAY 0.468085 (-5150 2900);
PAINT GREEN (-5150 2900);
DISPLAY INVISIBLE (-5150 2900);
FORCEPROP 1 LAST BODY_TYPE PLUMBING
J 0
(-5135 2885);
DISPLAY 0.808511 (-5135 2885);
PAINT GREEN (-5135 2885);
DISPLAY INVISIBLE (-5135 2885);
FORCEPROP 1 LAST PATH I82
J 0
(-5115 2900);
DISPLAY 0.808511 (-5115 2900);
PAINT GREEN (-5115 2900);
DISPLAY INVISIBLE (-5115 2900);
FORCEADD CAPACITOR..2
(-5100 3450);
FORCEPROP 1 LAST $LOCATION C197
J 0
(-5000 3450);
DISPLAY 1.212766 (-5000 3450);
PAINT GREEN (-5000 3450);
FORCEPROP 0 LAST CDS_LOCATION C197
J 0
(-5000 3700);
DISPLAY 1.021277 (-5000 3700);
DISPLAY INVISIBLE (-5000 3700);
FORCEPROP 0 LAST $SEC 1
J 0
(-5000 3700);
DISPLAY 0.680851 (-5000 3700);
PAINT MONO (-5000 3700);
DISPLAY INVISIBLE (-5000 3700);
FORCEPROP 0 LAST CDS_SEC 1
J 0
(-5000 3700);
DISPLAY 1.021277 (-5000 3700);
DISPLAY INVISIBLE (-5000 3700);
FORCEPROP 0 LASTPIN (-5100 3550) $PN 1
R 1
J 0
(-5110 3560);
DISPLAY 0.680851 (-5110 3560);
PAINT MONO (-5110 3560);
FORCEPROP 0 LASTPIN (-5100 3300) $PN 2
R 1
J 2
(-5110 3290);
DISPLAY 0.680851 (-5110 3290);
PAINT MONO (-5110 3290);
FORCEPROP 0 LAST PACKAGE 0402
J 0
(-5000 3550);
DISPLAY 1.021277 (-5000 3550);
FORCEPROP 0 LAST VOLTAGE 25V
J 0
(-5000 3650);
DISPLAY 1.021277 (-5000 3650);
FORCEPROP 1 LAST VALUE 0.1UF
J 0
(-5000 3350);
DISPLAY 1.212766 (-5000 3350);
PAINT GREEN (-5000 3350);
FORCEPROP 1 LAST CLS_PN G105-0B104-EK
J 0
(-5200 3500);
DISPLAY 1.212766 (-5200 3500);
PAINT GREEN (-5200 3500);
DISPLAY INVISIBLE (-5200 3500);
FORCEPROP 2 LAST CDS_LIB passive
J 0
(-5100 3450);
DISPLAY INVISIBLE (-5100 3450);
FORCEPROP 1 LAST CDS_LMAN_SYM_OUTLINE -50,0,50,-50
J 0
(-5100 3450);
DISPLAY 0.468085 (-5100 3450);
PAINT GREEN (-5100 3450);
DISPLAY INVISIBLE (-5100 3450);
FORCEPROP 1 LAST TOLERANCE 10%
J 0
(-5250 3550);
DISPLAY 1.212766 (-5250 3550);
PAINT GREEN (-5250 3550);
DISPLAY INVISIBLE (-5250 3550);
FORCEPROP 1 LAST PATH I83
J 0
(-5200 3500);
DISPLAY 1.212766 (-5200 3500);
PAINT GREEN (-5200 3500);
DISPLAY INVISIBLE (-5200 3500);
FORCEADD VCC..1
(-4350 8900);
FORCEPROP 3 LASTPIN (-4300 8850) SIG_NAME XP1R2V_FPGA\g
J 0
(-4290 8860);
DISPLAY 0.659574 (-4290 8860);
PAINT MONO (-4290 8860);
DISPLAY INVISIBLE (-4290 8860);
FORCEPROP 0 LAST VOLTAGE 1.2V
J 0
(-4450 9050);
DISPLAY 1.021277 (-4450 9050);
DISPLAY BOTH (-4450 9050);
FORCEPROP 1 LAST HDL_POWER XP1R2V_FPGA
J 1
(-4295 8955);
DISPLAY 1.021277 (-4295 8955);
PAINT GREEN (-4295 8955);
FORCEPROP 1 LAST CDS_LMAN_SYM_OUTLINE -250,250,250,-250
J 0
(-4350 8900);
DISPLAY 0.468085 (-4350 8900);
PAINT GREEN (-4350 8900);
DISPLAY INVISIBLE (-4350 8900);
FORCEPROP 2 LAST CDS_LIB cls
J 0
(-4350 8900);
DISPLAY INVISIBLE (-4350 8900);
FORCEPROP 1 LAST BODY_TYPE PLUMBING
J 0
(-4395 8857);
DISPLAY 0.340426 (-4395 8857);
PAINT GREEN (-4395 8857);
DISPLAY INVISIBLE (-4395 8857);
FORCEPROP 1 LAST PATH I84
J 0
(-4315 8990);
DISPLAY 0.808511 (-4315 8990);
PAINT GREEN (-4315 8990);
DISPLAY INVISIBLE (-4315 8990);
FORCEADD VCC..1
(-4200 4100);
FORCEPROP 3 LASTPIN (-4150 4050) SIG_NAME XP1R8V_FPGA\g
J 0
(-4140 4060);
DISPLAY 0.659574 (-4140 4060);
PAINT MONO (-4140 4060);
DISPLAY INVISIBLE (-4140 4060);
FORCEPROP 0 LAST VOLTAGE 1.8V
J 0
(-4300 4250);
DISPLAY 1.021277 (-4300 4250);
DISPLAY BOTH (-4300 4250);
FORCEPROP 1 LAST HDL_POWER XP1R8V_FPGA
J 1
(-4145 4155);
DISPLAY 1.021277 (-4145 4155);
PAINT GREEN (-4145 4155);
FORCEPROP 2 LAST CDS_LIB cls
J 0
(-4200 4100);
DISPLAY INVISIBLE (-4200 4100);
FORCEPROP 1 LAST CDS_LMAN_SYM_OUTLINE -250,250,250,-250
J 0
(-4200 4100);
DISPLAY 0.468085 (-4200 4100);
PAINT GREEN (-4200 4100);
DISPLAY INVISIBLE (-4200 4100);
FORCEPROP 1 LAST BODY_TYPE PLUMBING
J 0
(-4245 4057);
DISPLAY 0.340426 (-4245 4057);
PAINT GREEN (-4245 4057);
DISPLAY INVISIBLE (-4245 4057);
FORCEPROP 1 LAST PATH I86
J 0
(-4165 4190);
DISPLAY 0.808511 (-4165 4190);
PAINT GREEN (-4165 4190);
DISPLAY INVISIBLE (-4165 4190);
FORCEADD CAPACITOR..2
(-7650 6800);
FORCEPROP 1 LAST $LOCATION C192
J 0
(-7550 6850);
DISPLAY 1.212766 (-7550 6850);
PAINT GREEN (-7550 6850);
FORCEPROP 0 LAST CDS_LOCATION C192
J 0
(-7600 7000);
DISPLAY 1.021277 (-7600 7000);
DISPLAY INVISIBLE (-7600 7000);
FORCEPROP 0 LAST $SEC 1
J 0
(-7600 7000);
DISPLAY 0.680851 (-7600 7000);
PAINT MONO (-7600 7000);
DISPLAY INVISIBLE (-7600 7000);
FORCEPROP 0 LAST CDS_SEC 1
J 0
(-7600 7000);
DISPLAY 1.021277 (-7600 7000);
DISPLAY INVISIBLE (-7600 7000);
FORCEPROP 0 LASTPIN (-7650 6900) $PN 1
R 1
J 0
(-7660 6910);
DISPLAY 0.680851 (-7660 6910);
PAINT MONO (-7660 6910);
FORCEPROP 0 LASTPIN (-7650 6650) $PN 2
R 1
J 2
(-7660 6640);
DISPLAY 0.680851 (-7660 6640);
PAINT MONO (-7660 6640);
FORCEPROP 1 LAST VALUE 0.01UF
J 0
(-7550 6750);
DISPLAY 0.978723 (-7550 6750);
PAINT GREEN (-7550 6750);
FORCEPROP 0 LAST VOLTAGE 25V
J 0
(-7550 6950);
DISPLAY 1.021277 (-7550 6950);
FORCEPROP 0 LAST PACKAGE 0201
J 0
(-7550 6650);
DISPLAY 1.021277 (-7550 6650);
FORCEPROP 2 LAST CDS_LIB passive
J 0
(-7650 6800);
DISPLAY INVISIBLE (-7650 6800);
FORCEPROP 1 LAST CDS_LMAN_SYM_OUTLINE -50,0,50,-50
J 0
(-7650 6800);
DISPLAY 0.468085 (-7650 6800);
PAINT GREEN (-7650 6800);
DISPLAY INVISIBLE (-7650 6800);
FORCEPROP 1 LAST TOLERANCE 10%
J 0
(-7800 6900);
DISPLAY 1.212766 (-7800 6900);
PAINT GREEN (-7800 6900);
DISPLAY INVISIBLE (-7800 6900);
FORCEPROP 1 LAST CLS_PN G104-0B103-EK
J 0
(-7750 6850);
DISPLAY 1.212766 (-7750 6850);
PAINT GREEN (-7750 6850);
DISPLAY INVISIBLE (-7750 6850);
FORCEPROP 1 LAST PATH I9
J 0
(-7750 6850);
DISPLAY 1.212766 (-7750 6850);
PAINT GREEN (-7750 6850);
DISPLAY INVISIBLE (-7750 6850);
FORCEADD OFFPAGE_OUT..1
(-5750 2100);
FORCEPROP 2 LAST $XR3 32E2< 
J 0
(-5125 2100);
DISPLAY 0.638298 (-5125 2100);
PAINT MONO (-5125 2100);
FORCEPROP 2 LAST $XR2 31J2< 
J 0
(-5305 2100);
DISPLAY 0.638298 (-5305 2100);
PAINT MONO (-5305 2100);
FORCEPROP 2 LAST $XR1 31D3< 
J 0
(-5485 2100);
DISPLAY 0.638298 (-5485 2100);
PAINT MONO (-5485 2100);
FORCEPROP 2 LAST $XR0 25F6<> 
J 0
(-5695 2100);
DISPLAY 0.638298 (-5695 2100);
PAINT MONO (-5695 2100);
FORCEPROP 1 LAST BODY_TYPE COMMENT
J 0
(-5740 2235);
DISPLAY 0.808511 (-5740 2235);
PAINT GREEN (-5740 2235);
DISPLAY INVISIBLE (-5740 2235);
FORCEPROP 1 LAST CDS_LMAN_SYM_OUTLINE -50,50,50,-50
J 0
(-5750 2100);
DISPLAY 0.468085 (-5750 2100);
PAINT GREEN (-5750 2100);
DISPLAY INVISIBLE (-5750 2100);
FORCEPROP 2 LAST CDS_LIB cls
J 0
(-5750 2100);
DISPLAY INVISIBLE (-5750 2100);
FORCEPROP 1 LAST OFFPAGE TRUE
J 0
(-5740 2155);
DISPLAY 0.808511 (-5740 2155);
PAINT GREEN (-5740 2155);
DISPLAY INVISIBLE (-5740 2155);
FORCEPROP 2 LAST PATH I92
J 0
(-5700 2200);
DISPLAY 1.021277 (-5700 2200);
DISPLAY INVISIBLE (-5700 2200);
FORCEADD CAPACITOR..2
(-13200 8450);
FORCEPROP 1 LAST $LOCATION C180
J 0
(-13150 8300);
DISPLAY 1.212766 (-13150 8300);
PAINT GREEN (-13150 8300);
FORCEPROP 0 LAST CDS_LOCATION C180
J 0
(-13100 8500);
DISPLAY 1.021277 (-13100 8500);
DISPLAY INVISIBLE (-13100 8500);
FORCEPROP 0 LAST $SEC 1
J 0
(-13100 8500);
DISPLAY 0.680851 (-13100 8500);
PAINT MONO (-13100 8500);
DISPLAY INVISIBLE (-13100 8500);
FORCEPROP 0 LAST CDS_SEC 1
J 0
(-13100 8500);
DISPLAY 1.021277 (-13100 8500);
DISPLAY INVISIBLE (-13100 8500);
FORCEPROP 0 LASTPIN (-13200 8550) $PN 1
R 1
J 0
(-13210 8560);
DISPLAY 0.680851 (-13210 8560);
PAINT MONO (-13210 8560);
FORCEPROP 0 LASTPIN (-13200 8300) $PN 2
R 1
J 2
(-13210 8290);
DISPLAY 0.680851 (-13210 8290);
PAINT MONO (-13210 8290);
FORCEPROP 0 LAST VOLTAGE 10V
J 0
(-13100 8650);
DISPLAY 1.021277 (-13100 8650);
FORCEPROP 0 LAST PACKAGE 0805
J 0
(-13100 8550);
DISPLAY 1.021277 (-13100 8550);
FORCEPROP 1 LAST VALUE 22UF
J 0
(-13100 8400);
DISPLAY 1.212766 (-13100 8400);
PAINT GREEN (-13100 8400);
FORCEPROP 2 LAST CDS_LIB passive
J 0
(-13200 8450);
DISPLAY INVISIBLE (-13200 8450);
FORCEPROP 1 LAST CDS_LMAN_SYM_OUTLINE -50,0,50,-50
J 0
(-13200 8450);
DISPLAY 0.468085 (-13200 8450);
PAINT GREEN (-13200 8450);
DISPLAY INVISIBLE (-13200 8450);
FORCEPROP 1 LAST CLS_PN G107-0F226-CM
J 0
(-13300 8500);
DISPLAY 1.212766 (-13300 8500);
PAINT GREEN (-13300 8500);
DISPLAY INVISIBLE (-13300 8500);
FORCEPROP 1 LAST TOLERANCE 20%
J 0
(-13350 8550);
DISPLAY 1.212766 (-13350 8550);
PAINT GREEN (-13350 8550);
DISPLAY INVISIBLE (-13350 8550);
FORCEPROP 1 LAST PATH I93
J 0
(-13300 8500);
DISPLAY 1.212766 (-13300 8500);
PAINT GREEN (-13300 8500);
DISPLAY INVISIBLE (-13300 8500);
FORCEADD CAPACITOR..2
(-12750 8450);
FORCEPROP 1 LAST $LOCATION C182
J 0
(-12700 8300);
DISPLAY 1.212766 (-12700 8300);
PAINT GREEN (-12700 8300);
FORCEPROP 0 LAST CDS_LOCATION C182
J 0
(-12700 8600);
DISPLAY 1.021277 (-12700 8600);
DISPLAY INVISIBLE (-12700 8600);
FORCEPROP 0 LAST $SEC 1
J 0
(-12700 8600);
DISPLAY 0.680851 (-12700 8600);
PAINT MONO (-12700 8600);
DISPLAY INVISIBLE (-12700 8600);
FORCEPROP 0 LAST CDS_SEC 1
J 0
(-12700 8600);
DISPLAY 1.021277 (-12700 8600);
DISPLAY INVISIBLE (-12700 8600);
FORCEPROP 0 LASTPIN (-12750 8550) $PN 1
R 1
J 0
(-12760 8560);
DISPLAY 0.680851 (-12760 8560);
PAINT MONO (-12760 8560);
FORCEPROP 0 LASTPIN (-12750 8300) $PN 2
R 1
J 2
(-12760 8290);
DISPLAY 0.680851 (-12760 8290);
PAINT MONO (-12760 8290);
FORCEPROP 0 LAST VOLTAGE 25V
J 0
(-12650 8650);
DISPLAY 1.021277 (-12650 8650);
FORCEPROP 1 LAST VALUE 0.1UF
J 0
(-12650 8450);
DISPLAY 1.212766 (-12650 8450);
PAINT GREEN (-12650 8450);
FORCEPROP 0 LAST PACKAGE 0402
J 0
(-12650 8550);
DISPLAY 1.021277 (-12650 8550);
FORCEPROP 1 LAST TOLERANCE 10%
J 0
(-12900 8550);
DISPLAY 1.212766 (-12900 8550);
PAINT GREEN (-12900 8550);
DISPLAY INVISIBLE (-12900 8550);
FORCEPROP 1 LAST CLS_PN G105-0B104-EK
J 0
(-12850 8500);
DISPLAY 1.212766 (-12850 8500);
PAINT GREEN (-12850 8500);
DISPLAY INVISIBLE (-12850 8500);
FORCEPROP 1 LAST CDS_LMAN_SYM_OUTLINE -50,0,50,-50
J 0
(-12750 8450);
DISPLAY 0.468085 (-12750 8450);
PAINT GREEN (-12750 8450);
DISPLAY INVISIBLE (-12750 8450);
FORCEPROP 2 LAST CDS_LIB passive
J 0
(-12750 8450);
DISPLAY INVISIBLE (-12750 8450);
FORCEPROP 1 LAST PATH I94
J 0
(-12850 8500);
DISPLAY 1.212766 (-12850 8500);
PAINT GREEN (-12850 8500);
DISPLAY INVISIBLE (-12850 8500);
FORCEADD GND_SG..1
(-12800 8100);
FORCEPROP 3 LASTPIN (-12750 8150) SIG_NAME SG\g
J 0
(-12740 8160);
DISPLAY 0.659574 (-12740 8160);
PAINT MONO (-12740 8160);
DISPLAY INVISIBLE (-12740 8160);
FORCEPROP 1 LAST HDL_POWER SG
J 1
(-12745 8005);
DISPLAY 0.808511 (-12745 8005);
PAINT GREEN (-12745 8005);
FORCEPROP 1 LAST CDS_LMAN_SYM_OUTLINE 0,0,100,-50
J 0
(-12800 8100);
DISPLAY 0.468085 (-12800 8100);
PAINT GREEN (-12800 8100);
DISPLAY INVISIBLE (-12800 8100);
FORCEPROP 2 LAST CDS_LIB cls
J 0
(-12800 8100);
DISPLAY INVISIBLE (-12800 8100);
FORCEPROP 1 LAST BODY_TYPE PLUMBING
J 0
(-12785 8085);
DISPLAY 0.808511 (-12785 8085);
PAINT GREEN (-12785 8085);
DISPLAY INVISIBLE (-12785 8085);
FORCEPROP 1 LAST PATH I95
J 0
(-12765 8100);
DISPLAY 0.808511 (-12765 8100);
PAINT GREEN (-12765 8100);
DISPLAY INVISIBLE (-12765 8100);
FORCEADD GND_SG..1
(-12700 3200);
FORCEPROP 3 LASTPIN (-12650 3250) SIG_NAME SG\g
J 0
(-12640 3260);
DISPLAY 0.659574 (-12640 3260);
PAINT MONO (-12640 3260);
DISPLAY INVISIBLE (-12640 3260);
FORCEPROP 1 LAST HDL_POWER SG
J 1
(-12645 3105);
DISPLAY 0.808511 (-12645 3105);
PAINT GREEN (-12645 3105);
FORCEPROP 1 LAST CDS_LMAN_SYM_OUTLINE 0,0,100,-50
J 0
(-12700 3200);
DISPLAY 0.468085 (-12700 3200);
PAINT GREEN (-12700 3200);
DISPLAY INVISIBLE (-12700 3200);
FORCEPROP 2 LAST CDS_LIB cls
J 0
(-12700 3200);
DISPLAY INVISIBLE (-12700 3200);
FORCEPROP 1 LAST BODY_TYPE PLUMBING
J 0
(-12685 3185);
DISPLAY 0.808511 (-12685 3185);
PAINT GREEN (-12685 3185);
DISPLAY INVISIBLE (-12685 3185);
FORCEPROP 1 LAST PATH I96
J 0
(-12665 3200);
DISPLAY 0.808511 (-12665 3200);
PAINT GREEN (-12665 3200);
DISPLAY INVISIBLE (-12665 3200);
FORCEADD CAPACITOR..2
(-13100 3550);
FORCEPROP 1 LAST $LOCATION C181
J 0
(-13050 3400);
DISPLAY 1.212766 (-13050 3400);
PAINT GREEN (-13050 3400);
FORCEPROP 0 LAST CDS_LOCATION C181
J 0
(-13000 3600);
DISPLAY 1.021277 (-13000 3600);
DISPLAY INVISIBLE (-13000 3600);
FORCEPROP 0 LAST $SEC 1
J 0
(-13000 3600);
DISPLAY 0.680851 (-13000 3600);
PAINT MONO (-13000 3600);
DISPLAY INVISIBLE (-13000 3600);
FORCEPROP 0 LAST CDS_SEC 1
J 0
(-13000 3600);
DISPLAY 1.021277 (-13000 3600);
DISPLAY INVISIBLE (-13000 3600);
FORCEPROP 0 LASTPIN (-13100 3650) $PN 1
R 1
J 0
(-13110 3660);
DISPLAY 0.680851 (-13110 3660);
PAINT MONO (-13110 3660);
FORCEPROP 0 LASTPIN (-13100 3400) $PN 2
R 1
J 2
(-13110 3390);
DISPLAY 0.680851 (-13110 3390);
PAINT MONO (-13110 3390);
FORCEPROP 0 LAST PACKAGE 0805
J 0
(-13000 3650);
DISPLAY 1.021277 (-13000 3650);
FORCEPROP 1 LAST VALUE 22UF
J 0
(-13000 3500);
DISPLAY 1.212766 (-13000 3500);
PAINT GREEN (-13000 3500);
FORCEPROP 0 LAST VOLTAGE 10V
J 0
(-13000 3750);
DISPLAY 1.021277 (-13000 3750);
FORCEPROP 2 LAST CDS_LIB passive
J 0
(-13100 3550);
DISPLAY INVISIBLE (-13100 3550);
FORCEPROP 1 LAST CDS_LMAN_SYM_OUTLINE -50,0,50,-50
J 0
(-13100 3550);
DISPLAY 0.468085 (-13100 3550);
PAINT GREEN (-13100 3550);
DISPLAY INVISIBLE (-13100 3550);
FORCEPROP 1 LAST CLS_PN G107-0F226-CM
J 0
(-13200 3600);
DISPLAY 1.212766 (-13200 3600);
PAINT GREEN (-13200 3600);
DISPLAY INVISIBLE (-13200 3600);
FORCEPROP 1 LAST TOLERANCE 20%
J 0
(-13250 3650);
DISPLAY 1.212766 (-13250 3650);
PAINT GREEN (-13250 3650);
DISPLAY INVISIBLE (-13250 3650);
FORCEPROP 1 LAST PATH I97
J 0
(-13200 3600);
DISPLAY 1.212766 (-13200 3600);
PAINT GREEN (-13200 3600);
DISPLAY INVISIBLE (-13200 3600);
FORCEADD CAPACITOR..2
(-12650 3550);
FORCEPROP 1 LAST $LOCATION C183
J 0
(-12600 3400);
DISPLAY 1.212766 (-12600 3400);
PAINT GREEN (-12600 3400);
FORCEPROP 0 LAST CDS_LOCATION C183
J 0
(-12600 3700);
DISPLAY 1.021277 (-12600 3700);
DISPLAY INVISIBLE (-12600 3700);
FORCEPROP 0 LAST $SEC 1
J 0
(-12600 3700);
DISPLAY 0.680851 (-12600 3700);
PAINT MONO (-12600 3700);
DISPLAY INVISIBLE (-12600 3700);
FORCEPROP 0 LAST CDS_SEC 1
J 0
(-12600 3700);
DISPLAY 1.021277 (-12600 3700);
DISPLAY INVISIBLE (-12600 3700);
FORCEPROP 0 LASTPIN (-12650 3650) $PN 1
R 1
J 0
(-12660 3660);
DISPLAY 0.680851 (-12660 3660);
PAINT MONO (-12660 3660);
FORCEPROP 0 LASTPIN (-12650 3400) $PN 2
R 1
J 2
(-12660 3390);
DISPLAY 0.680851 (-12660 3390);
PAINT MONO (-12660 3390);
FORCEPROP 0 LAST VOLTAGE 25V
J 0
(-12550 3700);
FORCEPROP 1 LAST VALUE 0.1UF
J 0
(-12600 3600);
DISPLAY 1.212766 (-12600 3600);
PAINT GREEN (-12600 3600);
FORCEPROP 0 LAST PACKAGE 0402
J 0
(-12500 3500);
FORCEPROP 2 LAST CDS_LIB passive
J 0
(-12650 3550);
DISPLAY INVISIBLE (-12650 3550);
FORCEPROP 1 LAST CDS_LMAN_SYM_OUTLINE -50,0,50,-50
J 0
(-12650 3550);
DISPLAY 0.468085 (-12650 3550);
PAINT GREEN (-12650 3550);
DISPLAY INVISIBLE (-12650 3550);
FORCEPROP 0 LAST MATERIAL X7R
J 0
(-12550 3800);
DISPLAY INVISIBLE (-12550 3800);
FORCEPROP 1 LAST CLS_PN G105-0B104-EK
J 0
(-12750 3600);
DISPLAY 1.212766 (-12750 3600);
PAINT GREEN (-12750 3600);
DISPLAY INVISIBLE (-12750 3600);
FORCEPROP 1 LAST TOLERANCE 10%
J 0
(-12800 3650);
DISPLAY 1.212766 (-12800 3650);
PAINT GREEN (-12800 3650);
DISPLAY INVISIBLE (-12800 3650);
FORCEPROP 1 LAST PATH I98
J 0
(-12750 3600);
DISPLAY 1.212766 (-12750 3600);
PAINT GREEN (-12750 3600);
DISPLAY INVISIBLE (-12750 3600);
FORCEADD SHEET_A1..1
(100 -100);
FORCEPROP 2 LAST CUSTOM_TXT_CDS <XR_PAGE_TITLE>
J 0
(-15470 11250);
DISPLAY 0.638298 (-15470 11250);
PAINT PINK (-15470 11250);
FORCEPROP 1 LAST CUSTOM_TXT_CDS <DOCNO>
J 0
(-1950 285);
DISPLAY 0.978723 (-1950 285);
FORCEPROP 1 LAST CUSTOM_TXT_CDS <CON_PAGE_NUM>
J 0
(-2055 -50);
DISPLAY 0.978723 (-2055 -50);
FORCEPROP 1 LAST CUSTOM_TXT_CDS <DATE>
J 0
(-600 75);
DISPLAY 0.978723 (-600 75);
FORCEPROP 1 LAST CUSTOM_TXT_CDS <TITLE>
J 1
(-1685 530);
DISPLAY 0.978723 (-1685 530);
FORCEPROP 1 LAST CUSTOM_TXT_CDS <DESIGNER>
J 0
(-600 500);
DISPLAY 0.978723 (-600 500);
FORCEPROP 1 LAST CUSTOM_TXT_CDS <CON_TOTAL_PAGES>
J 0
(-1745 -50);
DISPLAY 0.808511 (-1745 -50);
FORCEPROP 1 LAST CUSTOM_TXT_CDS <ASSY_PN>
J 0
(-1950 75);
DISPLAY 0.978723 (-1950 75);
FORCEPROP 1 LAST CUSTOM_TXT_CDS <DOCREV>
J 0
(-600 275);
DISPLAY 0.978723 (-600 275);
FORCEPROP 1 LAST TITLE XP1R2V_FPGA & XP1R8V_FPGA
J 0
(-3600 850);
DISPLAY 3.042553 (-3600 850);
PAINT GREEN (-3600 850);
FORCEPROP 1 LAST CDS_LMAN_SYM_OUTLINE -15850,11500,200,-200
J 0
(100 -100);
DISPLAY 0.468085 (100 -100);
PAINT GREEN (100 -100);
DISPLAY INVISIBLE (100 -100);
FORCEPROP 2 LAST CDS_LIB cls
J 0
(100 -100);
DISPLAY INVISIBLE (100 -100);
FORCEPROP 2 LAST PAGE_BORDER TRUE
J 0
(-10600 7830);
DISPLAY 0.638298 (-10600 7830);
PAINT PINK (-10600 7830);
DISPLAY INVISIBLE (-10600 7830);
FORCEPROP 1 LAST TITLE XP1R2V_FPGA
J 0
(100 -100);
PAINT MONO (100 -100);
DISPLAY INVISIBLE (100 -100);
FORCEPROP 1 LAST COMMENT_BODY TRUE
J 0
(110 -45);
DISPLAY 0.808511 (110 -45);
DISPLAY INVISIBLE (110 -45);
FORCEPROP 2 LAST CDS_XR_PAGE_TITLE CR-30 : @TIMECARD_LIB.TIMECARD(SCH_1):PAGE30
J 0
(-15470 11250);
DISPLAY 0.638298 (-15470 11250);
PAINT PINK (-15470 11250);
DISPLAY INVISIBLE (-15470 11250);
WIRE 16 -1 (-7650 6650)(-7650 6600);
WIRE 16 -1 (-7600 2500)(-7600 2600);
WIRE 16 -1 (-7650 1750)(-7650 1700);
WIRE 16 -1 (-10650 2000)(-10650 2200);
WIRE 16 -1 (-10700 6900)(-10700 7100);
WIRE 16 -1 (-7600 7400)(-7600 7500);
WIRE 16 -1 (-12650 3300)(-13100 3300);
WIRE 16 -1 (-12650 3400)(-12650 3300);
WIRE 16 -1 (-12650 3250)(-12650 3300);
WIRE 16 -1 (-13100 3300)(-13100 3400);
WIRE 16 -1 (-12750 8200)(-13200 8200);
WIRE 16 -1 (-12750 8150)(-12750 8200);
WIRE 16 -1 (-12750 8300)(-12750 8200);
WIRE 16 -1 (-13200 8200)(-13200 8300);
WIRE 16 -1 (-8850 3250)(-8500 3250);
WIRE 16 -1 (-8500 3250)(-8500 3350);
WIRE 16 -1 (-8850 3350)(-8500 3350);
WIRE 16 -1 (-8500 3850)(-8500 3350);
WIRE 16 -1 (-8500 3850)(-6350 3850);
WIRE 16 -1 (-6350 3850)(-5700 3850);
WIRE 16 -1 (-6350 3550)(-6350 3850);
WIRE 16 -1 (-5100 3850)(-5700 3850);
WIRE 16 -1 (-5700 3550)(-5700 3850);
WIRE 16 -1 (-4150 3850)(-5100 3850);
WIRE 16 -1 (-5100 3550)(-5100 3850);
WIRE 16 -1 (-4150 4050)(-4150 3850);
WIRE 16 -1 (-8900 8150)(-8550 8150);
WIRE 16 -1 (-8550 8150)(-8550 8250);
WIRE 16 -1 (-8900 8250)(-8550 8250);
WIRE 16 -1 (-8550 8750)(-8550 8250);
WIRE 16 -1 (-8550 8750)(-6400 8750);
WIRE 16 -1 (-6400 8750)(-5750 8750);
WIRE 16 -1 (-6400 8450)(-6400 8750);
WIRE 16 -1 (-5150 8750)(-5750 8750);
WIRE 16 -1 (-5750 8450)(-5750 8750);
WIRE 16 -1 (-4300 8750)(-5150 8750);
WIRE 16 -1 (-5150 8450)(-5150 8750);
WIRE 16 -1 (-4300 8850)(-4300 8750);
WIRE 16 -1 (-5100 2950)(-5100 3050);
WIRE 16 -1 (-5100 3300)(-5100 3050);
WIRE 16 -1 (-5700 3050)(-5100 3050);
WIRE 16 -1 (-5700 3300)(-5700 3050);
WIRE 16 -1 (-6300 2650)(-6300 2500);
WIRE 16 -1 (-6300 2500)(-6050 2500);
WIRE 16 -1 (-6050 2500)(-6050 2650);
WIRE 16 -1 (-6050 2450)(-6050 2500);
WIRE 16 -1 (-8550 1850)(-8550 2550);
WIRE 16 -1 (-8550 2650)(-8550 2550);
WIRE 16 -1 (-8850 2550)(-8550 2550);
WIRE 16 -1 (-8850 2650)(-8550 2650);
WIRE 16 -1 (-8600 6750)(-8600 7450);
WIRE 16 -1 (-8600 7550)(-8600 7450);
WIRE 16 -1 (-8900 7450)(-8600 7450);
WIRE 16 -1 (-8900 7550)(-8600 7550);
WIRE 16 -1 (-10750 3250)(-10750 3150);
WIRE 16 -1 (-10750 3400)(-10750 3250);
WIRE 16 -1 (-11200 3250)(-10750 3250);
WIRE 16 -1 (-11200 3400)(-11200 3250);
WIRE 16 -1 (-11800 2000)(-11800 2200);
WIRE 16 -1 (-11200 2200)(-11800 2200);
WIRE 16 -1 (-11800 2200)(-11800 2400);
WIRE 16 -1 (-11200 2450)(-11200 2200);
WIRE 16 -1 (-10800 8300)(-10800 8150);
WIRE 16 -1 (-10800 8150)(-10800 8050);
WIRE 16 -1 (-11250 8150)(-10800 8150);
WIRE 16 -1 (-11250 8300)(-11250 8150);
WIRE 16 -1 (-13200 3950)(-13200 3850);
WIRE 16 -1 (-13100 3850)(-13200 3850);
WIRE 16 -1 (-12650 3850)(-13100 3850);
WIRE 16 -1 (-13100 3850)(-13100 3650);
WIRE 16 -1 (-12550 3850)(-12650 3850);
WIRE 16 -1 (-12650 3850)(-12650 3650);
WIRE 16 -1 (-13300 8900)(-13300 8750);
WIRE 16 -1 (-13200 8750)(-13300 8750);
WIRE 16 -1 (-12750 8750)(-13200 8750);
WIRE 16 -1 (-13200 8750)(-13200 8550);
WIRE 16 -1 (-12600 8750)(-12750 8750);
WIRE 16 -1 (-12750 8750)(-12750 8550);
WIRE 16 -1 (-5750 8200)(-5750 7950);
WIRE 16 -1 (-5750 7950)(-5150 7950);
WIRE 16 -1 (-5150 8200)(-5150 7950);
WIRE 16 -1 (-5150 7750)(-5150 7950);
WIRE 16 -1 (-6350 7550)(-6350 7400);
WIRE 16 -1 (-6350 7400)(-6100 7400);
WIRE 16 -1 (-6100 7400)(-6100 7550);
WIRE 16 -1 (-6100 7350)(-6100 7400);
WIRE 16 -1 (-11300 7350)(-11300 7150);
WIRE 16 -1 (-11300 7150)(-11850 7150);
WIRE 16 -1 (-11850 6900)(-11850 7150);
WIRE 16 -1 (-11850 7150)(-11850 7400);
WIRE 16 -1 (-6850 2100)(-5800 2100);
FORCEPROP 2 LAST SIG_NAME XP1R8V_FPGA_PG
J 0
(-6560 2110);
DISPLAY 1.021277 (-6560 2110);
WIRE 16 -1 (-10650 2650)(-9950 2650);
WIRE 16 -1 (-10650 2450)(-10650 2650);
FORCEPROP 2 LAST SIG_NAME XP1R8V_SS
J 0
(-10560 2660);
DISPLAY 1.021277 (-10560 2660);
WIRE 16 -1 (-6100 7800)(-6100 7950);
WIRE 16 -1 (-6100 7950)(-6350 7950);
WIRE 16 -1 (-6350 7800)(-6350 7950);
WIRE 16 -1 (-6350 7950)(-6400 7950);
WIRE 16 -1 (-6400 8200)(-6400 7950);
WIRE 16 -1 (-8900 7950)(-6400 7950);
FORCEPROP 2 LAST SIG_NAME XP1R2V_FB
J 0
(-8810 7960);
DISPLAY 1.021277 (-8810 7960);
WIRE 16 -1 (-12300 7750)(-11850 7750);
WIRE 16 -1 (-11700 7750)(-11850 7750);
WIRE 16 -1 (-11850 7650)(-11850 7750);
WIRE 16 -1 (-11300 7750)(-11700 7750);
WIRE 16 -1 (-11700 8150)(-11700 7750);
WIRE 16 -1 (-11300 7600)(-11300 7750);
WIRE 16 -1 (-10000 7750)(-11300 7750);
FORCEPROP 2 LAST SIG_NAME XP1R2V_EN_R
J 0
(-10760 7760);
DISPLAY 1.021277 (-10760 7760);
WIRE 16 -1 (-10700 7550)(-10000 7550);
WIRE 16 -1 (-10700 7350)(-10700 7550);
FORCEPROP 2 LAST SIG_NAME XP1R2V_SS
J 0
(-10610 7560);
DISPLAY 1.021277 (-10610 7560);
WIRE 16 -1 (-6800 7000)(-5800 7000);
FORCEPROP 2 LAST SIG_NAME XP1R2V_FPGA_PG
J 0
(-6510 7010);
DISPLAY 1.021277 (-6510 7010);
WIRE 16 273 (-14750 5900)(-500 5900);
WIRE 16 -1 (-9950 3250)(-10300 3250);
WIRE 16 -1 (-10300 3250)(-10300 3350);
WIRE 16 -1 (-9950 3350)(-10300 3350);
WIRE 16 -1 (-10300 3850)(-10300 3350);
WIRE 16 -1 (-10300 3850)(-10750 3850);
WIRE 16 -1 (-10750 3650)(-10750 3850);
WIRE 16 -1 (-10750 3850)(-11200 3850);
WIRE 16 -1 (-11200 3650)(-11200 3850);
WIRE 16 -1 (-11200 3850)(-11850 3850);
FORCEPROP 2 LAST SIG_NAME XP1R8V_VIN
J 0
(-11460 3860);
DISPLAY 1.021277 (-11460 3860);
WIRE 16 -1 (-11850 3500)(-11850 3850);
WIRE 16 -1 (-12150 3850)(-11850 3850);
WIRE 16 -1 (-8150 2100)(-8150 2850);
WIRE 16 -1 (-8150 2100)(-7650 2100);
WIRE 16 -1 (-8150 2850)(-8850 2850);
FORCEPROP 2 LAST SIG_NAME XP1R8V_PG_R
J 0
(-8760 2860);
DISPLAY 1.021277 (-8760 2860);
WIRE 16 -1 (-7600 2100)(-7650 2100);
WIRE 16 -1 (-7650 2000)(-7650 2100);
WIRE 16 -1 (-7100 2100)(-7600 2100);
WIRE 16 -1 (-7600 2250)(-7600 2100);
WIRE 16 -1 (-12050 2850)(-11850 2850);
WIRE 16 -1 (-11850 3250)(-11850 2850);
WIRE 16 -1 (-11850 2850)(-11800 2850);
WIRE 16 -1 (-11800 2650)(-11800 2850);
WIRE 16 -1 (-11200 2850)(-11800 2850);
WIRE 16 -1 (-9950 2850)(-11200 2850);
FORCEPROP 2 LAST SIG_NAME XP1R8V_EN_R
J 0
(-10710 2860);
DISPLAY 1.021277 (-10710 2860);
WIRE 16 -1 (-11200 2700)(-11200 2850);
WIRE 16 -1 (-13550 2850)(-12300 2850);
FORCEPROP 2 LAST SIG_NAME XP1R2V_FPGA_PG
J 0
(-13410 2860);
DISPLAY 1.021277 (-13410 2860);
WIRE 16 -1 (-7600 7150)(-7600 7000);
WIRE 16 -1 (-7050 7000)(-7600 7000);
WIRE 16 -1 (-7600 7000)(-7650 7000);
WIRE 16 -1 (-7650 6900)(-7650 7000);
WIRE 16 -1 (-8250 7000)(-7650 7000);
WIRE 16 -1 (-8250 7000)(-8250 7750);
WIRE 16 -1 (-8250 7750)(-8900 7750);
FORCEPROP 2 LAST SIG_NAME XP1R2V_PG_R
J 0
(-8810 7760);
DISPLAY 1.021277 (-8810 7760);
WIRE 16 -1 (-10000 8150)(-10350 8150);
WIRE 16 -1 (-10350 8150)(-10350 8250);
WIRE 16 -1 (-10000 8250)(-10350 8250);
WIRE 16 -1 (-10350 8750)(-10350 8250);
WIRE 16 -1 (-10350 8750)(-10800 8750);
WIRE 16 -1 (-10800 8550)(-10800 8750);
WIRE 16 -1 (-10800 8750)(-11250 8750);
WIRE 16 -1 (-11250 8550)(-11250 8750);
WIRE 16 -1 (-11700 8750)(-11250 8750);
FORCEPROP 2 LAST SIG_NAME XP1R2V_VIN
J 0
(-11510 8760);
DISPLAY 1.021277 (-11510 8760);
WIRE 16 -1 (-12200 8750)(-11700 8750);
WIRE 16 -1 (-11700 8400)(-11700 8750);
WIRE 16 -1 (-13600 7750)(-12550 7750);
FORCEPROP 2 LAST SIG_NAME XP1R0V_FPGA_PG
J 0
(-13510 7760);
DISPLAY 1.021277 (-13510 7760);
WIRE 8 -1 (-3150 7750)(-2300 7750);
WIRE 8 -1 (-3150 7750)(-3150 7900);
WIRE 8 -1 (-2300 7750)(-1000 7750);
WIRE 8 -1 (-2300 7750)(-2300 7900);
WIRE 8 -1 (-3150 7900)(-2300 7900);
WIRE 8 -1 (-2300 7900)(-1000 7900);
WIRE 8 -1 (-2300 7900)(-2300 8050);
WIRE 8 -1 (-1000 7750)(-1000 7900);
WIRE 8 -1 (-3150 7900)(-3150 8050);
WIRE 8 -1 (-3150 8050)(-3150 8200);
WIRE 8 -1 (-3150 8050)(-2300 8050);
WIRE 8 -1 (-1000 7900)(-1000 8050);
WIRE 8 -1 (-2300 8050)(-2300 8200);
WIRE 8 -1 (-2300 8050)(-1000 8050);
WIRE 8 -1 (-1000 8050)(-1000 8200);
WIRE 8 -1 (-3150 8200)(-2300 8200);
WIRE 8 -1 (-2300 8200)(-1000 8200);
WIRE 8 -1 (-2300 8200)(-2300 8350);
WIRE 8 -1 (-3150 8350)(-3150 8200);
WIRE 8 -1 (-3150 8350)(-2300 8350);
WIRE 8 -1 (-3150 8500)(-3150 8350);
WIRE 8 -1 (-2300 8350)(-2300 8500);
WIRE 8 -1 (-2300 8350)(-1000 8350);
WIRE 8 -1 (-1000 8350)(-1000 8200);
WIRE 8 -1 (-1000 8500)(-1000 8350);
WIRE 8 -1 (-2300 8500)(-3150 8500);
WIRE 8 -1 (-1000 8500)(-2300 8500);
WIRE 16 -1 (-6050 2900)(-6050 3050);
WIRE 16 -1 (-6050 3050)(-6300 3050);
WIRE 16 -1 (-6300 2900)(-6300 3050);
WIRE 16 -1 (-6300 3050)(-6350 3050);
WIRE 16 -1 (-6350 3300)(-6350 3050);
WIRE 16 -1 (-8850 3050)(-6350 3050);
FORCEPROP 2 LAST SIG_NAME XP1R8V_FB
J 0
(-8760 3060);
DISPLAY 1.021277 (-8760 3060);
WIRE 8 -1 (-3150 3150)(-2300 3150);
WIRE 8 -1 (-3150 3150)(-3150 3300);
WIRE 8 -1 (-2300 3150)(-1000 3150);
WIRE 8 -1 (-2300 3150)(-2300 3300);
WIRE 8 -1 (-3150 3300)(-2300 3300);
WIRE 8 -1 (-2300 3300)(-1000 3300);
WIRE 8 -1 (-2300 3300)(-2300 3450);
WIRE 8 -1 (-1000 3150)(-1000 3300);
WIRE 8 -1 (-3150 3300)(-3150 3450);
WIRE 8 -1 (-3150 3450)(-2300 3450);
WIRE 8 -1 (-3150 3450)(-3150 3600);
WIRE 8 -1 (-1000 3300)(-1000 3450);
WIRE 8 -1 (-2300 3450)(-1000 3450);
WIRE 8 -1 (-2300 3450)(-2300 3600);
WIRE 8 -1 (-3150 3600)(-2300 3600);
WIRE 8 -1 (-2300 3600)(-1000 3600);
WIRE 8 -1 (-2300 3600)(-2300 3750);
WIRE 8 -1 (-1000 3450)(-1000 3600);
WIRE 8 -1 (-3150 3750)(-3150 3600);
WIRE 8 -1 (-3150 3750)(-2300 3750);
WIRE 8 -1 (-3150 3900)(-3150 3750);
WIRE 8 -1 (-1000 3750)(-1000 3600);
WIRE 8 -1 (-2300 3750)(-2300 3900);
WIRE 8 -1 (-2300 3750)(-1000 3750);
WIRE 8 -1 (-1000 3900)(-1000 3750);
WIRE 8 -1 (-2300 3900)(-3150 3900);
WIRE 8 -1 (-1000 3900)(-2300 3900);
DOT 1 (-10350 8250);
DOT 1 (-5100 3050);
DOT 1 (-11800 2200);
DOT 1 (-7650 7000);
DOT 1 (-11700 7750);
DOT 1 (-11850 3850);
DOT 1 (-6350 3050);
DOT 1 (-6300 3050);
DOT 1 (-11800 2850);
DOT 1 (-11850 7750);
DOT 1 (-1000 8350);
DOT 1 (-1000 8200);
DOT 1 (-1000 7900);
DOT 1 (-1000 8050);
DOT 1 (-2300 8500);
DOT 1 (-2300 8350);
DOT 1 (-2300 8200);
DOT 1 (-2300 7900);
DOT 1 (-2300 8050);
DOT 1 (-2300 7750);
DOT 1 (-3150 8200);
DOT 1 (-3150 7900);
DOT 1 (-3150 8050);
DOT 1 (-5150 8750);
DOT 1 (-5750 8750);
DOT 1 (-6400 8750);
DOT 1 (-5150 7950);
DOT 1 (-6350 7950);
DOT 1 (-6100 7400);
DOT 1 (-6400 7950);
DOT 1 (-10800 8750);
DOT 1 (-11250 8750);
DOT 1 (-11700 8750);
DOT 1 (-8550 8250);
DOT 1 (-8600 7450);
DOT 1 (-10800 8150);
DOT 1 (-11300 7750);
DOT 1 (-11850 7150);
DOT 1 (-1000 3750);
DOT 1 (-1000 3600);
DOT 1 (-1000 3300);
DOT 1 (-1000 3450);
DOT 1 (-2300 3900);
DOT 1 (-2300 3750);
DOT 1 (-2300 3600);
DOT 1 (-2300 3450);
DOT 1 (-2300 3300);
DOT 1 (-2300 3150);
DOT 1 (-3150 3750);
DOT 1 (-3150 3600);
DOT 1 (-3150 3300);
DOT 1 (-3150 3450);
DOT 1 (-5100 3850);
DOT 1 (-5700 3850);
DOT 1 (-6050 2500);
DOT 1 (-6350 3850);
DOT 1 (-8500 3350);
DOT 1 (-8550 2550);
DOT 1 (-10300 3350);
DOT 1 (-10750 3850);
DOT 1 (-11200 3850);
DOT 1 (-10750 3250);
DOT 1 (-11200 2850);
DOT 1 (-3150 8350);
DOT 1 (-7600 7000);
DOT 1 (-7600 2100);
DOT 1 (-7650 2100);
DOT 1 (-12750 8750);
DOT 1 (-13200 8750);
DOT 1 (-12750 8200);
DOT 1 (-12650 3850);
DOT 1 (-13100 3850);
DOT 1 (-12650 3300);
DOT 1 (-11850 2850);
FORCENOTE
VFB=0.5V
(-6900 8050) 0;
DISPLAY LEFT (-6900 8050);
DISPLAY 1.021277 (-6900 8050);
FORCENOTE
SS: 2.5MS
(-10200 7200) 0;
DISPLAY LEFT (-10200 7200);
DISPLAY 1.595745 (-10200 7200);
FORCENOTE
VOUT=(RTOP/RBOTTOM+1)*VFB
(-7700 8200) 0;
DISPLAY LEFT (-7700 8200);
DISPLAY 1.021277 (-7700 8200);
FORCENOTE
0.3601A
(-4850 3900) 0;
DISPLAY LEFT (-4850 3900);
DISPLAY 1.595745 (-4850 3900);
FORCENOTE
VOUT=(RTOP/RBOTTOM+1)*VFB
(-7650 3300) 0;
DISPLAY LEFT (-7650 3300);
DISPLAY 1.021277 (-7650 3300);
FORCENOTE
SS: 2.5MS
(-9900 2250) 0;
DISPLAY LEFT (-9900 2250);
DISPLAY 1.595745 (-9900 2250);
FORCENOTE
VOUT
(-2900 8100) 0;
DISPLAY LEFT (-2900 8100);
DISPLAY 1.595745 (-2900 8100);
FORCENOTE
IOUT
(-2900 7950) 0;
DISPLAY LEFT (-2900 7950);
DISPLAY 1.595745 (-2900 7950);
FORCENOTE
XP1R8V_FPGA
(-9250 4900) 0;
DISPLAY LEFT (-9250 4900);
DISPLAY 6.148936 (-9250 4900);
FORCENOTE
VFB=0.5V
(-6850 3150) 0;
DISPLAY LEFT (-6850 3150);
DISPLAY 1.021277 (-6850 3150);
FORCENOTE
XP1R2V_FPGA
(-3100 8550) 0;
DISPLAY LEFT (-3100 8550);
DISPLAY 3.148936 (-3100 8550);
PAINT VIOLET (-3100 8550);
FORCENOTE
1.2V
(-2050 8100) 0;
DISPLAY LEFT (-2050 8100);
DISPLAY 1.595745 (-2050 8100);
FORCENOTE
3.3V
(-2050 8250) 0;
DISPLAY LEFT (-2050 8250);
DISPLAY 1.595745 (-2050 8250);
FORCENOTE
VALUE(TYP)
(-2050 8400) 0;
DISPLAY LEFT (-2050 8400);
DISPLAY 1.595745 (-2050 8400);
FORCENOTE
0.065A
(-2050 7950) 0;
DISPLAY LEFT (-2050 7950);
DISPLAY 1.595745 (-2050 7950);
FORCENOTE
1.75A
(-2050 7800) 0;
DISPLAY LEFT (-2050 7800);
DISPLAY 1.595745 (-2050 7800);
FORCENOTE
VIN
(-2900 8250) 0;
DISPLAY LEFT (-2900 8250);
DISPLAY 1.595745 (-2900 8250);
FORCENOTE
PARAMETERS
(-3100 8400) 0;
DISPLAY LEFT (-3100 8400);
DISPLAY 1.595745 (-3100 8400);
FORCENOTE
OCP
(-2900 7800) 0;
DISPLAY LEFT (-2900 7800);
DISPLAY 1.595745 (-2900 7800);
FORCENOTE
0.065A
(-4900 8800) 0;
DISPLAY LEFT (-4900 8800);
DISPLAY 1.595745 (-4900 8800);
FORCENOTE
RTOP
(-6700 8350) 0;
DISPLAY LEFT (-6700 8350);
DISPLAY 1.021277 (-6700 8350);
FORCENOTE
XP1R2V_FPGA
(-9150 9850) 0;
DISPLAY LEFT (-9150 9850);
DISPLAY 6.148936 (-9150 9850);
FORCENOTE
VALUE(TYP)
(-2050 3800) 0;
DISPLAY LEFT (-2050 3800);
DISPLAY 1.595745 (-2050 3800);
FORCENOTE
VIN
(-2900 3650) 0;
DISPLAY LEFT (-2900 3650);
DISPLAY 1.595745 (-2900 3650);
FORCENOTE
IOUT
(-2900 3350) 0;
DISPLAY LEFT (-2900 3350);
DISPLAY 1.595745 (-2900 3350);
FORCENOTE
VOUT
(-2900 3500) 0;
DISPLAY LEFT (-2900 3500);
DISPLAY 1.595745 (-2900 3500);
FORCENOTE
OCP
(-2900 3200) 0;
DISPLAY LEFT (-2900 3200);
DISPLAY 1.595745 (-2900 3200);
FORCENOTE
PARAMETERS
(-3100 3800) 0;
DISPLAY LEFT (-3100 3800);
DISPLAY 1.595745 (-3100 3800);
FORCENOTE
RTOP
(-6650 3450) 0;
DISPLAY LEFT (-6650 3450);
DISPLAY 1.021277 (-6650 3450);
FORCENOTE
1.75A
(-2050 3200) 0;
DISPLAY LEFT (-2050 3200);
DISPLAY 1.595745 (-2050 3200);
FORCENOTE
0.3601A
(-2050 3350) 0;
DISPLAY LEFT (-2050 3350);
DISPLAY 1.595745 (-2050 3350);
FORCENOTE
1.8V
(-2050 3500) 0;
DISPLAY LEFT (-2050 3500);
DISPLAY 1.595745 (-2050 3500);
FORCENOTE
3.3V
(-2050 3650) 0;
DISPLAY LEFT (-2050 3650);
DISPLAY 1.595745 (-2050 3650);
FORCENOTE
XP1R8V_FPGA
(-3100 3950) 0;
DISPLAY LEFT (-3100 3950);
DISPLAY 3.148936 (-3100 3950);
PAINT VIOLET (-3100 3950);
QUIT
